FILE_TYPE = MACRO_DRAWING;
SET COLOR_WIRE YELLOW;
SET COLOR_PROP ORANGE;
SET COLOR_DOT WHITE;
SET COLOR_ARC YELLOW;
SET COLOR_BODY GREEN;
SET COLOR_NOTE PURPLE;
SET PROP_DISPLAY VALUE;
SET PAGE_NUMBER P228;
FORCEADD UNIVERSAL_POWER..1
(5550 6400);
FORCEPROP 3 LASTPIN (5550 6350) SIG_NAME P3V3_AUX\g
J 0
(5560 6360);
DISPLAY 0.659574 (5560 6360);
PAINT MONO (5560 6360);
DISPLAY INVISIBLE (5560 6360);
FORCEPROP 1 LAST HDL_POWER P3V3_AUX
J 1
(5550 6450);
DISPLAY 0.702128 (5550 6450);
PAINT GREEN (5550 6450);
FORCEPROP 2 LAST CDS_LIB logical_power
J 0
(5550 6400);
PAINT MONO (5550 6400);
DISPLAY INVISIBLE (5550 6400);
FORCEPROP 1 LAST PATH I1
J 0
(5600 6425);
DISPLAY 0.872340 (5600 6425);
PAINT AQUA (5600 6425);
DISPLAY INVISIBLE (5600 6425);
FORCEADD OFFPAGE..5
(3500 5775);
FORCEPROP 2 LAST $XR1 241 
J 0
(3095 5775);
DISPLAY 0.638298 (3095 5775);
PAINT MONO (3095 5775);
FORCEPROP 2 LAST $XR0 240 
J 0
(3215 5775);
DISPLAY 0.638298 (3215 5775);
PAINT MONO (3215 5775);
FORCEPROP 2 LAST CDS_LIB standard
J 0
(3500 5775);
PAINT MONO (3500 5775);
DISPLAY INVISIBLE (3500 5775);
FORCEPROP 1 LAST COMMENT_BODY TRUE
J 0
(3600 5700);
DISPLAY 0.872340 (3600 5700);
PAINT PEACH (3600 5700);
DISPLAY INVISIBLE (3600 5700);
FORCEPROP 1 LAST OFFPAGE TRUE
J 0
(3825 5650);
DISPLAY 0.872340 (3825 5650);
PAINT GREEN (3825 5650);
DISPLAY INVISIBLE (3825 5650);
FORCEPROP 2 LAST PATH I10
J 0
(3200 5825);
DISPLAY 1.021277 (3200 5825);
DISPLAY INVISIBLE (3200 5825);
FORCEADD OFFPAGE..3
R 2
(-2050 2675);
FORCEPROP 2 LAST $XR0 233 
J 0
(-2330 2675);
DISPLAY 0.638298 (-2330 2675);
PAINT MONO (-2330 2675);
FORCEPROP 2 LAST PATH I100
J 0
(-2375 2725);
DISPLAY 1.021277 (-2375 2725);
DISPLAY INVISIBLE (-2375 2725);
FORCEPROP 1 LAST OFFPAGE TRUE
J 2
(-2375 2550);
DISPLAY 0.872340 (-2375 2550);
DISPLAY INVISIBLE (-2375 2550);
FORCEPROP 1 LAST COMMENT_BODY TRUE
J 2
(-2000 2575);
DISPLAY 0.872340 (-2000 2575);
PAINT GREEN (-2000 2575);
DISPLAY INVISIBLE (-2000 2575);
FORCEPROP 2 LAST CDS_LIB standard
J 0
(-2050 2675);
PAINT MONO (-2050 2675);
DISPLAY INVISIBLE (-2050 2675);
FORCEADD OFFPAGE..1
(-2050 2725);
FORCEPROP 2 LAST $XR0 233 
J 0
(-2302 2725);
DISPLAY 0.638298 (-2302 2725);
PAINT MONO (-2302 2725);
FORCEPROP 2 LAST PATH I101
J 0
(-2325 2775);
DISPLAY 1.021277 (-2325 2775);
DISPLAY INVISIBLE (-2325 2775);
FORCEPROP 1 LAST COMMENT_BODY TRUE
J 0
(-1925 2625);
DISPLAY 0.872340 (-1925 2625);
PAINT GREEN (-1925 2625);
DISPLAY INVISIBLE (-1925 2625);
FORCEPROP 1 LAST OFFPAGE TRUE
J 0
(-1725 2600);
DISPLAY 0.872340 (-1725 2600);
PAINT GREEN (-1725 2600);
DISPLAY INVISIBLE (-1725 2600);
FORCEPROP 2 LAST CDS_LIB standard
J 0
(-2050 2725);
PAINT MONO (-2050 2725);
DISPLAY INVISIBLE (-2050 2725);
FORCEADD OFFPAGE..5
(3500 5825);
FORCEPROP 2 LAST $XR1 241 
J 0
(3095 5825);
DISPLAY 0.638298 (3095 5825);
PAINT MONO (3095 5825);
FORCEPROP 2 LAST $XR0 240 
J 0
(3215 5825);
DISPLAY 0.638298 (3215 5825);
PAINT MONO (3215 5825);
FORCEPROP 2 LAST CDS_LIB standard
J 0
(3500 5825);
PAINT MONO (3500 5825);
DISPLAY INVISIBLE (3500 5825);
FORCEPROP 1 LAST COMMENT_BODY TRUE
J 0
(3600 5750);
DISPLAY 0.872340 (3600 5750);
PAINT PEACH (3600 5750);
DISPLAY INVISIBLE (3600 5750);
FORCEPROP 1 LAST OFFPAGE TRUE
J 0
(3825 5700);
DISPLAY 0.872340 (3825 5700);
PAINT GREEN (3825 5700);
DISPLAY INVISIBLE (3825 5700);
FORCEPROP 2 LAST PATH I11
J 0
(3225 5875);
DISPLAY 1.021277 (3225 5875);
DISPLAY INVISIBLE (3225 5875);
FORCEADD OFFPAGE..5
(3500 5575);
FORCEPROP 2 LAST $XR2 241 
J 0
(2975 5575);
DISPLAY 0.638298 (2975 5575);
PAINT MONO (2975 5575);
FORCEPROP 2 LAST $XR1 183 
J 0
(3095 5575);
DISPLAY 0.638298 (3095 5575);
PAINT MONO (3095 5575);
FORCEPROP 2 LAST $XR0 240 
J 0
(3215 5575);
DISPLAY 0.638298 (3215 5575);
PAINT MONO (3215 5575);
FORCEPROP 2 LAST PATH I12
J 0
(3225 5625);
DISPLAY 1.021277 (3225 5625);
DISPLAY INVISIBLE (3225 5625);
FORCEPROP 1 LAST OFFPAGE TRUE
J 0
(3825 5450);
DISPLAY 0.872340 (3825 5450);
PAINT GREEN (3825 5450);
DISPLAY INVISIBLE (3825 5450);
FORCEPROP 1 LAST COMMENT_BODY TRUE
J 0
(3600 5500);
DISPLAY 0.872340 (3600 5500);
PAINT PEACH (3600 5500);
DISPLAY INVISIBLE (3600 5500);
FORCEPROP 2 LAST CDS_LIB standard
J 0
(3500 5575);
PAINT MONO (3500 5575);
DISPLAY INVISIBLE (3500 5575);
FORCEADD OFFPAGE..5
(3500 5525);
FORCEPROP 2 LAST $XR2 241 
J 0
(2975 5525);
DISPLAY 0.638298 (2975 5525);
PAINT MONO (2975 5525);
FORCEPROP 2 LAST $XR1 240 
J 0
(3095 5525);
DISPLAY 0.638298 (3095 5525);
PAINT MONO (3095 5525);
FORCEPROP 2 LAST $XR0 183 
J 0
(3215 5525);
DISPLAY 0.638298 (3215 5525);
PAINT MONO (3215 5525);
FORCEPROP 2 LAST PATH I13
J 0
(3200 5575);
DISPLAY 1.021277 (3200 5575);
DISPLAY INVISIBLE (3200 5575);
FORCEPROP 1 LAST OFFPAGE TRUE
J 0
(3825 5400);
DISPLAY 0.872340 (3825 5400);
PAINT GREEN (3825 5400);
DISPLAY INVISIBLE (3825 5400);
FORCEPROP 1 LAST COMMENT_BODY TRUE
J 0
(3600 5450);
DISPLAY 0.872340 (3600 5450);
PAINT PEACH (3600 5450);
DISPLAY INVISIBLE (3600 5450);
FORCEPROP 2 LAST CDS_LIB standard
J 0
(3500 5525);
PAINT MONO (3500 5525);
DISPLAY INVISIBLE (3500 5525);
FORCEADD OFFPAGE..2
(1350 5800);
FORCEPROP 2 LAST $XR0 183 
J 0
(1539 5800);
DISPLAY 0.638298 (1539 5800);
PAINT MONO (1539 5800);
FORCEPROP 2 LAST PATH I16
J 0
(1550 5850);
DISPLAY 1.021277 (1550 5850);
DISPLAY INVISIBLE (1550 5850);
FORCEPROP 1 LAST OFFPAGE TRUE
J 0
(1675 5675);
DISPLAY 0.872340 (1675 5675);
PAINT GREEN (1675 5675);
DISPLAY INVISIBLE (1675 5675);
FORCEPROP 1 LAST COMMENT_BODY TRUE
J 0
(1305 5705);
DISPLAY 0.872340 (1305 5705);
PAINT GREEN (1305 5705);
DISPLAY INVISIBLE (1305 5705);
FORCEPROP 2 LAST CDS_LIB standard
J 0
(1350 5800);
PAINT MONO (1350 5800);
DISPLAY INVISIBLE (1350 5800);
FORCEADD OFFPAGE..3
(1350 5750);
FORCEPROP 2 LAST $XR0 183 
J 0
(1564 5750);
DISPLAY 0.638298 (1564 5750);
PAINT MONO (1564 5750);
FORCEPROP 2 LAST PATH I17
J 0
(1575 5800);
DISPLAY 1.021277 (1575 5800);
DISPLAY INVISIBLE (1575 5800);
FORCEPROP 1 LAST COMMENT_BODY TRUE
J 0
(1300 5650);
DISPLAY 0.872340 (1300 5650);
PAINT GREEN (1300 5650);
DISPLAY INVISIBLE (1300 5650);
FORCEPROP 1 LAST OFFPAGE TRUE
J 0
(1675 5625);
DISPLAY 0.872340 (1675 5625);
PAINT GREEN (1675 5625);
DISPLAY INVISIBLE (1675 5625);
FORCEPROP 2 LAST CDS_LIB standard
J 0
(1350 5750);
PAINT MONO (1350 5750);
DISPLAY INVISIBLE (1350 5750);
FORCEADD Q_RES..1
(5000 4925);
FORCEPROP 1 LAST PART_NUMBER CS22202JB07
J 0
(4900 4975);
DISPLAY 0.510638 (4900 4975);
DISPLAY INVISIBLE (4900 4975);
FORCEPROP 1 LAST VALUE 2.2K
J 2
(5225 4925);
DISPLAY 0.510638 (5225 4925);
FORCEPROP 1 LAST TOLERANCE 5%
J 0
(5225 4925);
DISPLAY 0.510638 (5225 4925);
FORCEPROP 1 LAST MATERIAL EMPTY
J 0
(5300 4925);
DISPLAY 0.510638 (5300 4925);
PAINT RED (5300 4925);
FORCEPROP 1 LAST $LOCATION R601
J 0
(4750 4925);
DISPLAY 0.638298 (4750 4925);
FORCEPROP 1 LASTPIN (4900 4925) $PN 1
J 0
(4912 4937);
DISPLAY 0.787234 (4912 4937);
FORCEPROP 1 LASTPIN (5100 4925) $PN 2
J 0
(5062 4937);
DISPLAY 0.787234 (5062 4937);
FORCEPROP 2 LAST CDS_LIB pure_quanta
J 0
(5000 4925);
PAINT MONO (5000 4925);
DISPLAY INVISIBLE (5000 4925);
FORCEPROP 1 LAST PACK_TYPE 0402LF
J 0
(4900 5025);
DISPLAY 0.510638 (4900 5025);
DISPLAY INVISIBLE (4900 5025);
FORCEPROP 1 LAST WATTAGE 1/16W
J 2
(5200 5025);
DISPLAY 0.510638 (5200 5025);
DISPLAY INVISIBLE (5200 5025);
FORCEPROP 1 LAST PATH I172
J 0
(4950 5075);
DISPLAY 0.978723 (4950 5075);
PAINT WHITE (4950 5075);
DISPLAY INVISIBLE (4950 5075);
FORCEPROP 1 LAST $LOCATION R601
J 0
(4950 5125);
DISPLAY 1.021277 (4950 5125);
DISPLAY INVISIBLE (4950 5125);
FORCEPROP 2 LAST CDS_LOCATION R601
J 0
(4950 5125);
DISPLAY 1.021277 (4950 5125);
DISPLAY INVISIBLE (4950 5125);
FORCEPROP 2 LAST $SEC 1
J 0
(4950 5125);
DISPLAY 0.680851 (4950 5125);
PAINT MONO (4950 5125);
DISPLAY INVISIBLE (4950 5125);
FORCEPROP 2 LAST CDS_SEC 1
J 0
(4950 5125);
DISPLAY 1.021277 (4950 5125);
DISPLAY INVISIBLE (4950 5125);
FORCEADD Q_RES..1
(5000 4975);
FORCEPROP 1 LAST PART_NUMBER CS22202JB07
J 0
(4850 5050);
DISPLAY 0.510638 (4850 5050);
DISPLAY INVISIBLE (4850 5050);
FORCEPROP 1 LAST MATERIAL EMPTY
J 0
(5300 4975);
DISPLAY 0.510638 (5300 4975);
PAINT RED (5300 4975);
FORCEPROP 1 LAST TOLERANCE 5%
J 0
(5225 4975);
DISPLAY 0.510638 (5225 4975);
FORCEPROP 1 LAST WATTAGE 1/16W
J 2
(5150 5100);
DISPLAY 0.510638 (5150 5100);
FORCEPROP 1 LAST PACK_TYPE 0402LF
J 0
(4850 5100);
DISPLAY 0.510638 (4850 5100);
FORCEPROP 1 LAST VALUE 2.2K
J 2
(5225 4975);
DISPLAY 0.510638 (5225 4975);
FORCEPROP 1 LAST $LOCATION R592
J 0
(4750 4975);
DISPLAY 0.638298 (4750 4975);
FORCEPROP 1 LASTPIN (4900 4975) $PN 1
J 0
(4912 4987);
DISPLAY 0.787234 (4912 4987);
FORCEPROP 1 LASTPIN (5100 4975) $PN 2
J 0
(5062 4987);
DISPLAY 0.787234 (5062 4987);
FORCEPROP 2 LAST CDS_LIB pure_quanta
J 0
(5000 4975);
PAINT MONO (5000 4975);
DISPLAY INVISIBLE (5000 4975);
FORCEPROP 1 LAST PATH I173
J 0
(4950 5125);
DISPLAY 0.978723 (4950 5125);
PAINT WHITE (4950 5125);
DISPLAY INVISIBLE (4950 5125);
FORCEPROP 1 LAST $LOCATION R592
J 0
(4950 5175);
DISPLAY 1.021277 (4950 5175);
DISPLAY INVISIBLE (4950 5175);
FORCEPROP 2 LAST CDS_LOCATION R592
J 0
(4950 5175);
DISPLAY 1.021277 (4950 5175);
DISPLAY INVISIBLE (4950 5175);
FORCEPROP 2 LAST $SEC 1
J 0
(4950 5175);
DISPLAY 0.680851 (4950 5175);
PAINT MONO (4950 5175);
DISPLAY INVISIBLE (4950 5175);
FORCEPROP 2 LAST CDS_SEC 1
J 0
(4950 5175);
DISPLAY 1.021277 (4950 5175);
DISPLAY INVISIBLE (4950 5175);
FORCEADD Q_RES..1
(5000 4325);
FORCEPROP 1 LAST PART_NUMBER CS22202JB07
J 0
(4900 4375);
DISPLAY 0.510638 (4900 4375);
DISPLAY INVISIBLE (4900 4375);
FORCEPROP 1 LAST VALUE 2.2K
J 2
(5225 4325);
DISPLAY 0.510638 (5225 4325);
FORCEPROP 1 LAST MATERIAL EMPTY
J 0
(5300 4325);
DISPLAY 0.510638 (5300 4325);
PAINT RED (5300 4325);
FORCEPROP 1 LAST TOLERANCE 5%
J 0
(5225 4325);
DISPLAY 0.510638 (5225 4325);
FORCEPROP 1 LAST $LOCATION R1460
J 0
(4750 4325);
DISPLAY 0.638298 (4750 4325);
FORCEPROP 1 LASTPIN (4900 4325) $PN 1
J 0
(4912 4337);
DISPLAY 0.787234 (4912 4337);
FORCEPROP 1 LASTPIN (5100 4325) $PN 2
J 0
(5062 4337);
DISPLAY 0.787234 (5062 4337);
FORCEPROP 1 LAST PACK_TYPE 0402LF
J 0
(4900 4425);
DISPLAY 0.510638 (4900 4425);
DISPLAY INVISIBLE (4900 4425);
FORCEPROP 1 LAST WATTAGE 1/16W
J 2
(5200 4425);
DISPLAY 0.510638 (5200 4425);
DISPLAY INVISIBLE (5200 4425);
FORCEPROP 2 LAST CDS_LIB pure_quanta
J 0
(5000 4325);
PAINT MONO (5000 4325);
DISPLAY INVISIBLE (5000 4325);
FORCEPROP 1 LAST PATH I176
J 0
(4950 4475);
DISPLAY 0.978723 (4950 4475);
PAINT WHITE (4950 4475);
DISPLAY INVISIBLE (4950 4475);
FORCEPROP 2 LAST CDS_LOCATION R1460
J 0
(4950 4525);
DISPLAY 1.021277 (4950 4525);
DISPLAY INVISIBLE (4950 4525);
FORCEPROP 2 LAST $SEC 1
J 0
(4950 4525);
DISPLAY 0.680851 (4950 4525);
PAINT MONO (4950 4525);
DISPLAY INVISIBLE (4950 4525);
FORCEPROP 2 LAST CDS_SEC 1
J 0
(4950 4525);
DISPLAY 1.021277 (4950 4525);
DISPLAY INVISIBLE (4950 4525);
FORCEADD Q_RES..1
(5000 4375);
FORCEPROP 1 LAST PART_NUMBER CS22202JB07
J 0
(4850 4450);
DISPLAY 0.510638 (4850 4450);
DISPLAY INVISIBLE (4850 4450);
FORCEPROP 1 LAST MATERIAL EMPTY
J 0
(5300 4375);
DISPLAY 0.510638 (5300 4375);
PAINT RED (5300 4375);
FORCEPROP 1 LAST TOLERANCE 5%
J 0
(5225 4375);
DISPLAY 0.510638 (5225 4375);
FORCEPROP 1 LAST VALUE 2.2K
J 2
(5225 4375);
DISPLAY 0.510638 (5225 4375);
FORCEPROP 1 LAST PACK_TYPE 0402LF
J 0
(4850 4500);
DISPLAY 0.510638 (4850 4500);
FORCEPROP 1 LAST WATTAGE 1/16W
J 2
(5150 4500);
DISPLAY 0.510638 (5150 4500);
FORCEPROP 1 LAST $LOCATION R1336
J 0
(4750 4375);
DISPLAY 0.638298 (4750 4375);
FORCEPROP 1 LASTPIN (4900 4375) $PN 1
J 0
(4912 4387);
DISPLAY 0.787234 (4912 4387);
FORCEPROP 1 LASTPIN (5100 4375) $PN 2
J 0
(5062 4387);
DISPLAY 0.787234 (5062 4387);
FORCEPROP 2 LAST CDS_LIB pure_quanta
J 0
(5000 4375);
PAINT MONO (5000 4375);
DISPLAY INVISIBLE (5000 4375);
FORCEPROP 1 LAST PATH I177
J 0
(4950 4525);
DISPLAY 0.978723 (4950 4525);
PAINT WHITE (4950 4525);
DISPLAY INVISIBLE (4950 4525);
FORCEPROP 2 LAST CDS_LOCATION R1336
J 0
(4950 4575);
DISPLAY 1.021277 (4950 4575);
DISPLAY INVISIBLE (4950 4575);
FORCEPROP 2 LAST $SEC 1
J 0
(4950 4575);
DISPLAY 0.680851 (4950 4575);
PAINT MONO (4950 4575);
DISPLAY INVISIBLE (4950 4575);
FORCEPROP 2 LAST CDS_SEC 1
J 0
(4950 4575);
DISPLAY 1.021277 (4950 4575);
DISPLAY INVISIBLE (4950 4575);
FORCEADD OFFPAGE..5
(3500 4975);
FORCEPROP 2 LAST $XR1 245 
J 0
(3095 4975);
DISPLAY 0.638298 (3095 4975);
PAINT MONO (3095 4975);
FORCEPROP 2 LAST $XR0 240 
J 0
(3215 4975);
DISPLAY 0.638298 (3215 4975);
PAINT MONO (3215 4975);
FORCEPROP 1 LAST OFFPAGE TRUE
J 0
(3825 4850);
DISPLAY 0.872340 (3825 4850);
PAINT GREEN (3825 4850);
DISPLAY INVISIBLE (3825 4850);
FORCEPROP 1 LAST COMMENT_BODY TRUE
J 0
(3600 4900);
DISPLAY 0.872340 (3600 4900);
PAINT PEACH (3600 4900);
DISPLAY INVISIBLE (3600 4900);
FORCEPROP 2 LAST PATH I178
J 0
(3200 5025);
DISPLAY 1.021277 (3200 5025);
DISPLAY INVISIBLE (3200 5025);
FORCEPROP 2 LAST CDS_LIB standard
J 0
(3500 4975);
DISPLAY INVISIBLE (3500 4975);
FORCEADD OFFPAGE..5
(3500 4925);
FORCEPROP 2 LAST $XR1 245 
J 0
(3095 4925);
DISPLAY 0.638298 (3095 4925);
PAINT MONO (3095 4925);
FORCEPROP 2 LAST $XR0 240 
J 0
(3215 4925);
DISPLAY 0.638298 (3215 4925);
PAINT MONO (3215 4925);
FORCEPROP 1 LAST OFFPAGE TRUE
J 0
(3825 4800);
DISPLAY 0.872340 (3825 4800);
PAINT GREEN (3825 4800);
DISPLAY INVISIBLE (3825 4800);
FORCEPROP 1 LAST COMMENT_BODY TRUE
J 0
(3600 4850);
DISPLAY 0.872340 (3600 4850);
PAINT PEACH (3600 4850);
DISPLAY INVISIBLE (3600 4850);
FORCEPROP 2 LAST PATH I179
J 0
(3175 4975);
DISPLAY 1.021277 (3175 4975);
DISPLAY INVISIBLE (3175 4975);
FORCEPROP 2 LAST CDS_LIB standard
J 0
(3500 4925);
DISPLAY INVISIBLE (3500 4925);
FORCEADD OFFPAGE..2
(1325 5500);
FORCEPROP 2 LAST $XR1 241 
J 0
(1634 5500);
DISPLAY 0.638298 (1634 5500);
PAINT MONO (1634 5500);
FORCEPROP 2 LAST $XR0 208 
J 0
(1514 5500);
DISPLAY 0.638298 (1514 5500);
PAINT MONO (1514 5500);
FORCEPROP 2 LAST CDS_LIB standard
J 0
(1325 5500);
PAINT MONO (1325 5500);
DISPLAY INVISIBLE (1325 5500);
FORCEPROP 1 LAST COMMENT_BODY TRUE
J 0
(1280 5405);
DISPLAY 0.872340 (1280 5405);
PAINT GREEN (1280 5405);
DISPLAY INVISIBLE (1280 5405);
FORCEPROP 1 LAST OFFPAGE TRUE
J 0
(1650 5375);
DISPLAY 0.872340 (1650 5375);
PAINT GREEN (1650 5375);
DISPLAY INVISIBLE (1650 5375);
FORCEPROP 2 LAST PATH I18
J 0
(1525 5550);
DISPLAY 1.021277 (1525 5550);
DISPLAY INVISIBLE (1525 5550);
FORCEADD OFFPAGE..5
(3500 4325);
FORCEPROP 2 LAST $XR1 240 
J 0
(3095 4325);
DISPLAY 0.638298 (3095 4325);
PAINT MONO (3095 4325);
FORCEPROP 2 LAST $XR0 234 
J 0
(3215 4325);
DISPLAY 0.638298 (3215 4325);
PAINT MONO (3215 4325);
FORCEPROP 2 LAST PATH I182
J 0
(3175 4375);
DISPLAY 1.021277 (3175 4375);
DISPLAY INVISIBLE (3175 4375);
FORCEPROP 2 LAST CDS_LIB standard
J 0
(3500 4325);
DISPLAY INVISIBLE (3500 4325);
FORCEPROP 1 LAST OFFPAGE TRUE
J 0
(3825 4200);
DISPLAY 0.872340 (3825 4200);
PAINT GREEN (3825 4200);
DISPLAY INVISIBLE (3825 4200);
FORCEPROP 1 LAST COMMENT_BODY TRUE
J 0
(3600 4250);
DISPLAY 0.872340 (3600 4250);
PAINT PEACH (3600 4250);
DISPLAY INVISIBLE (3600 4250);
FORCEADD OFFPAGE..5
(3500 4375);
FORCEPROP 2 LAST $XR1 234 
J 0
(3095 4375);
DISPLAY 0.638298 (3095 4375);
PAINT MONO (3095 4375);
FORCEPROP 2 LAST $XR0 240 
J 0
(3215 4375);
DISPLAY 0.638298 (3215 4375);
PAINT MONO (3215 4375);
FORCEPROP 2 LAST PATH I183
J 0
(3200 4425);
DISPLAY 1.021277 (3200 4425);
DISPLAY INVISIBLE (3200 4425);
FORCEPROP 2 LAST CDS_LIB standard
J 0
(3500 4375);
DISPLAY INVISIBLE (3500 4375);
FORCEPROP 1 LAST OFFPAGE TRUE
J 0
(3825 4250);
DISPLAY 0.872340 (3825 4250);
PAINT GREEN (3825 4250);
DISPLAY INVISIBLE (3825 4250);
FORCEPROP 1 LAST COMMENT_BODY TRUE
J 0
(3600 4300);
DISPLAY 0.872340 (3600 4300);
PAINT PEACH (3600 4300);
DISPLAY INVISIBLE (3600 4300);
FORCEADD OFFPAGE..3
(1325 5450);
FORCEPROP 2 LAST $XR1 241 
J 0
(1659 5450);
DISPLAY 0.638298 (1659 5450);
PAINT MONO (1659 5450);
FORCEPROP 2 LAST $XR0 208 
J 0
(1539 5450);
DISPLAY 0.638298 (1539 5450);
PAINT MONO (1539 5450);
FORCEPROP 2 LAST CDS_LIB standard
J 0
(1325 5450);
PAINT MONO (1325 5450);
DISPLAY INVISIBLE (1325 5450);
FORCEPROP 1 LAST OFFPAGE TRUE
J 0
(1650 5325);
DISPLAY 0.872340 (1650 5325);
PAINT GREEN (1650 5325);
DISPLAY INVISIBLE (1650 5325);
FORCEPROP 1 LAST COMMENT_BODY TRUE
J 0
(1275 5350);
DISPLAY 0.872340 (1275 5350);
PAINT GREEN (1275 5350);
DISPLAY INVISIBLE (1275 5350);
FORCEPROP 2 LAST PATH I19
J 0
(1550 5500);
DISPLAY 1.021277 (1550 5500);
DISPLAY INVISIBLE (1550 5500);
FORCEADD OFFPAGE..5
(3500 4025);
FORCEPROP 2 LAST $XR1 240 
J 0
(3095 4025);
DISPLAY 0.638298 (3095 4025);
PAINT MONO (3095 4025);
FORCEPROP 2 LAST $XR0 236 
J 0
(3215 4025);
DISPLAY 0.638298 (3215 4025);
PAINT MONO (3215 4025);
FORCEPROP 2 LAST PATH I199
J 0
(3200 4075);
DISPLAY 1.021277 (3200 4075);
DISPLAY INVISIBLE (3200 4075);
FORCEPROP 1 LAST COMMENT_BODY TRUE
J 0
(3600 3950);
DISPLAY 0.872340 (3600 3950);
PAINT PEACH (3600 3950);
DISPLAY INVISIBLE (3600 3950);
FORCEPROP 1 LAST OFFPAGE TRUE
J 0
(3825 3900);
DISPLAY 0.872340 (3825 3900);
PAINT GREEN (3825 3900);
DISPLAY INVISIBLE (3825 3900);
FORCEPROP 2 LAST CDS_LIB standard
J 0
(3500 4025);
DISPLAY INVISIBLE (3500 4025);
FORCEADD Q_RES..1
(5000 6075);
FORCEPROP 1 LAST PART_NUMBER CS22002FB07
J 0
(4875 6150);
DISPLAY 0.638298 (4875 6150);
DISPLAY INVISIBLE (4875 6150);
FORCEPROP 1 LAST MATERIAL EMPTY
J 0
(5375 6075);
DISPLAY 0.638298 (5375 6075);
PAINT RED (5375 6075);
FORCEPROP 1 LAST PACK_TYPE 0402LF
J 0
(4875 6200);
DISPLAY 0.638298 (4875 6200);
FORCEPROP 1 LAST WATTAGE 1/16W
J 2
(5250 6200);
DISPLAY 0.638298 (5250 6200);
FORCEPROP 1 LAST VALUE 2K
J 2
(5225 6075);
DISPLAY 0.638298 (5225 6075);
FORCEPROP 1 LAST TOLERANCE 1%
J 0
(5275 6075);
DISPLAY 0.638298 (5275 6075);
FORCEPROP 1 LAST $LOCATION R1319
J 0
(4725 6075);
DISPLAY 0.638298 (4725 6075);
FORCEPROP 1 LASTPIN (4900 6075) $PN 1
J 0
(4912 6087);
DISPLAY 0.787234 (4912 6087);
FORCEPROP 1 LASTPIN (5100 6075) $PN 2
J 0
(5062 6087);
DISPLAY 0.787234 (5062 6087);
FORCEPROP 1 LAST PATH I2
J 0
(4950 6225);
DISPLAY 0.978723 (4950 6225);
PAINT WHITE (4950 6225);
DISPLAY INVISIBLE (4950 6225);
FORCEPROP 2 LAST CDS_LIB pure_quanta
J 0
(5000 6075);
PAINT MONO (5000 6075);
DISPLAY INVISIBLE (5000 6075);
FORCEPROP 2 LAST CDS_LOCATION R1319
J 0
(4950 6275);
DISPLAY 1.021277 (4950 6275);
DISPLAY INVISIBLE (4950 6275);
FORCEPROP 2 LAST $SEC 1
J 0
(4950 6275);
DISPLAY 0.680851 (4950 6275);
PAINT MONO (4950 6275);
DISPLAY INVISIBLE (4950 6275);
FORCEPROP 2 LAST CDS_SEC 1
J 0
(4950 6275);
DISPLAY 1.021277 (4950 6275);
DISPLAY INVISIBLE (4950 6275);
FORCEADD OFFPAGE..2
(1325 5175);
FORCEPROP 2 LAST $XR0 237 
J 0
(1514 5175);
DISPLAY 0.638298 (1514 5175);
PAINT MONO (1514 5175);
FORCEPROP 2 LAST CDS_LIB standard
J 0
(1325 5175);
PAINT MONO (1325 5175);
DISPLAY INVISIBLE (1325 5175);
FORCEPROP 1 LAST COMMENT_BODY TRUE
J 0
(1280 5080);
DISPLAY 0.872340 (1280 5080);
PAINT GREEN (1280 5080);
DISPLAY INVISIBLE (1280 5080);
FORCEPROP 1 LAST OFFPAGE TRUE
J 0
(1650 5050);
DISPLAY 0.872340 (1650 5050);
PAINT GREEN (1650 5050);
DISPLAY INVISIBLE (1650 5050);
FORCEPROP 2 LAST PATH I20
J 0
(1525 5225);
DISPLAY 1.021277 (1525 5225);
DISPLAY INVISIBLE (1525 5225);
FORCEADD OFFPAGE..5
(3500 4075);
FORCEPROP 2 LAST $XR1 236 
J 0
(3095 4075);
DISPLAY 0.638298 (3095 4075);
PAINT MONO (3095 4075);
FORCEPROP 2 LAST $XR0 240 
J 0
(3215 4075);
DISPLAY 0.638298 (3215 4075);
PAINT MONO (3215 4075);
FORCEPROP 2 LAST PATH I201
J 0
(3200 4125);
DISPLAY 1.021277 (3200 4125);
DISPLAY INVISIBLE (3200 4125);
FORCEPROP 1 LAST COMMENT_BODY TRUE
J 0
(3600 4000);
DISPLAY 0.872340 (3600 4000);
PAINT PEACH (3600 4000);
DISPLAY INVISIBLE (3600 4000);
FORCEPROP 1 LAST OFFPAGE TRUE
J 0
(3825 3950);
DISPLAY 0.872340 (3825 3950);
PAINT GREEN (3825 3950);
DISPLAY INVISIBLE (3825 3950);
FORCEPROP 2 LAST CDS_LIB standard
J 0
(3500 4075);
DISPLAY INVISIBLE (3500 4075);
FORCEADD Q_RES..1
(5000 4075);
FORCEPROP 1 LAST PART_NUMBER CS22202JB07
J 0
(4850 4150);
DISPLAY 0.510638 (4850 4150);
DISPLAY INVISIBLE (4850 4150);
FORCEPROP 1 LAST PACK_TYPE 0402LF
J 0
(4850 4200);
DISPLAY 0.510638 (4850 4200);
FORCEPROP 1 LAST TOLERANCE 5%
J 0
(5225 4075);
DISPLAY 0.510638 (5225 4075);
FORCEPROP 1 LAST VALUE 2.2K
J 2
(5225 4075);
DISPLAY 0.510638 (5225 4075);
FORCEPROP 1 LAST MATERIAL EMPTY
J 0
(5300 4075);
DISPLAY 0.510638 (5300 4075);
PAINT RED (5300 4075);
FORCEPROP 1 LAST WATTAGE 1/16W
J 2
(5150 4200);
DISPLAY 0.510638 (5150 4200);
FORCEPROP 1 LAST $LOCATION R2212
J 0
(4750 4075);
DISPLAY 0.787234 (4750 4075);
FORCEPROP 1 LASTPIN (4900 4075) $PN 1
J 0
(4912 4087);
DISPLAY 0.787234 (4912 4087);
PAINT MONO (4912 4087);
FORCEPROP 1 LASTPIN (5100 4075) $PN 2
J 0
(5062 4087);
DISPLAY 0.787234 (5062 4087);
PAINT MONO (5062 4087);
FORCEPROP 2 LAST CDS_LIB pure_quanta
J 0
(5000 4075);
DISPLAY INVISIBLE (5000 4075);
FORCEPROP 1 LAST PATH I202
J 0
(4950 4225);
DISPLAY 0.978723 (4950 4225);
PAINT WHITE (4950 4225);
DISPLAY INVISIBLE (4950 4225);
FORCEPROP 0 LAST CDS_LOCATION R2212
J 0
(5150 4225);
DISPLAY 1.021277 (5150 4225);
DISPLAY INVISIBLE (5150 4225);
FORCEPROP 0 LAST $SEC 1
J 0
(5150 4225);
DISPLAY 0.680851 (5150 4225);
PAINT MONO (5150 4225);
DISPLAY INVISIBLE (5150 4225);
FORCEPROP 0 LAST CDS_SEC 1
J 0
(5150 4225);
DISPLAY 1.021277 (5150 4225);
DISPLAY INVISIBLE (5150 4225);
FORCEADD Q_RES..1
(5000 4025);
FORCEPROP 1 LAST PART_NUMBER CS22202JB07
J 0
(4900 4075);
DISPLAY 0.510638 (4900 4075);
DISPLAY INVISIBLE (4900 4075);
FORCEPROP 1 LAST TOLERANCE 5%
J 0
(5225 4025);
DISPLAY 0.510638 (5225 4025);
FORCEPROP 1 LAST VALUE 2.2K
J 2
(5225 4025);
DISPLAY 0.510638 (5225 4025);
FORCEPROP 1 LAST MATERIAL EMPTY
J 0
(5300 4025);
DISPLAY 0.510638 (5300 4025);
PAINT RED (5300 4025);
FORCEPROP 1 LAST $LOCATION R2213
J 0
(4750 4025);
DISPLAY 0.787234 (4750 4025);
FORCEPROP 1 LASTPIN (4900 4025) $PN 1
J 0
(4912 4037);
DISPLAY 0.787234 (4912 4037);
PAINT MONO (4912 4037);
FORCEPROP 1 LASTPIN (5100 4025) $PN 2
J 0
(5062 4037);
DISPLAY 0.787234 (5062 4037);
PAINT MONO (5062 4037);
FORCEPROP 1 LAST PACK_TYPE 0402LF
J 0
(4900 4125);
DISPLAY 0.510638 (4900 4125);
DISPLAY INVISIBLE (4900 4125);
FORCEPROP 1 LAST WATTAGE 1/16W
J 2
(5200 4125);
DISPLAY 0.510638 (5200 4125);
DISPLAY INVISIBLE (5200 4125);
FORCEPROP 2 LAST CDS_LIB pure_quanta
J 0
(5000 4025);
DISPLAY INVISIBLE (5000 4025);
FORCEPROP 1 LAST PATH I203
J 0
(4950 4175);
DISPLAY 0.978723 (4950 4175);
PAINT WHITE (4950 4175);
DISPLAY INVISIBLE (4950 4175);
FORCEPROP 0 LAST CDS_LOCATION R2213
J 0
(4750 4075);
DISPLAY 1.021277 (4750 4075);
DISPLAY INVISIBLE (4750 4075);
FORCEPROP 0 LAST $SEC 1
J 0
(4750 4075);
DISPLAY 0.680851 (4750 4075);
PAINT MONO (4750 4075);
DISPLAY INVISIBLE (4750 4075);
FORCEPROP 0 LAST CDS_SEC 1
J 0
(4750 4075);
DISPLAY 1.021277 (4750 4075);
DISPLAY INVISIBLE (4750 4075);
FORCEADD OFFPAGE..2
(1350 2450);
FORCEPROP 2 LAST $XR0 250 
J 0
(1539 2450);
DISPLAY 0.638298 (1539 2450);
PAINT MONO (1539 2450);
FORCEPROP 2 LAST CDS_LIB standard
J 0
(1350 2450);
PAINT MONO (1350 2450);
DISPLAY INVISIBLE (1350 2450);
FORCEPROP 1 LAST OFFPAGE TRUE
J 0
(1675 2325);
DISPLAY 1.170213 (1675 2325);
PAINT GREEN (1675 2325);
DISPLAY INVISIBLE (1675 2325);
FORCEPROP 1 LAST COMMENT_BODY TRUE
J 0
(1305 2355);
DISPLAY 1.170213 (1305 2355);
PAINT GREEN (1305 2355);
DISPLAY INVISIBLE (1305 2355);
FORCEPROP 2 LAST PATH I204
J 0
(2300 2500);
DISPLAY 1.021277 (2300 2500);
DISPLAY INVISIBLE (2300 2500);
FORCEADD OFFPAGE..3
(1350 2400);
FORCEPROP 2 LAST $XR0 250 
J 0
(1564 2400);
DISPLAY 0.638298 (1564 2400);
PAINT MONO (1564 2400);
FORCEPROP 1 LAST OFFPAGE TRUE
J 0
(1675 2275);
DISPLAY 0.872340 (1675 2275);
DISPLAY INVISIBLE (1675 2275);
FORCEPROP 1 LAST COMMENT_BODY TRUE
J 0
(1300 2300);
DISPLAY 0.872340 (1300 2300);
PAINT GREEN (1300 2300);
DISPLAY INVISIBLE (1300 2300);
FORCEPROP 2 LAST CDS_LIB standard
J 0
(1350 2400);
PAINT MONO (1350 2400);
DISPLAY INVISIBLE (1350 2400);
FORCEPROP 2 LAST PATH I205
J 0
(2475 2450);
DISPLAY 1.021277 (2475 2450);
DISPLAY INVISIBLE (2475 2450);
FORCEADD Q_RES..1
(-325 2450);
FORCEPROP 1 LAST PART_NUMBER CS03322FB03
J 0
(-450 2525);
DISPLAY 0.510638 (-450 2525);
DISPLAY INVISIBLE (-450 2525);
FORCEPROP 1 LAST WATTAGE 1/16W
J 2
(-150 2575);
DISPLAY 0.510638 (-150 2575);
FORCEPROP 1 LAST TOLERANCE 1%
J 0
(-100 2450);
DISPLAY 0.510638 (-100 2450);
FORCEPROP 1 LAST MATERIAL CHIP
J 0
(-25 2450);
DISPLAY 0.510638 (-25 2450);
FORCEPROP 1 LAST VALUE 33.2
J 2
(-125 2450);
DISPLAY 0.510638 (-125 2450);
FORCEPROP 1 LAST PACK_TYPE 0402LF
J 0
(-450 2575);
DISPLAY 0.510638 (-450 2575);
FORCEPROP 1 LAST $LOCATION R2449
J 0
(-575 2450);
DISPLAY 0.808511 (-575 2450);
FORCEPROP 1 LASTPIN (-425 2450) $PN 1
J 0
(-413 2462);
DISPLAY 0.787234 (-413 2462);
FORCEPROP 1 LASTPIN (-225 2450) $PN 2
J 0
(-263 2462);
DISPLAY 0.787234 (-263 2462);
FORCEPROP 2 LAST CDS_LIB pure_quanta
J 0
(-325 2450);
DISPLAY INVISIBLE (-325 2450);
FORCEPROP 1 LAST PATH I206
J 0
(-375 2600);
DISPLAY 0.978723 (-375 2600);
PAINT WHITE (-375 2600);
DISPLAY INVISIBLE (-375 2600);
FORCEPROP 0 LAST CDS_LOCATION R2449
J 0
(-150 2600);
DISPLAY 1.021277 (-150 2600);
DISPLAY INVISIBLE (-150 2600);
FORCEPROP 0 LAST $SEC 1
J 0
(-150 2600);
DISPLAY 0.680851 (-150 2600);
PAINT MONO (-150 2600);
DISPLAY INVISIBLE (-150 2600);
FORCEPROP 0 LAST CDS_SEC 1
J 0
(-150 2600);
DISPLAY 1.021277 (-150 2600);
DISPLAY INVISIBLE (-150 2600);
FORCEADD Q_RES..1
(-325 2400);
FORCEPROP 1 LAST PART_NUMBER CS03322FB03
J 0
(-450 2450);
DISPLAY 0.638298 (-450 2450);
DISPLAY INVISIBLE (-450 2450);
FORCEPROP 1 LAST TOLERANCE 1%
J 0
(-100 2400);
DISPLAY 0.510638 (-100 2400);
FORCEPROP 1 LAST MATERIAL CHIP
J 0
(-25 2400);
DISPLAY 0.510638 (-25 2400);
FORCEPROP 1 LAST VALUE 33.2
J 2
(-125 2400);
DISPLAY 0.510638 (-125 2400);
FORCEPROP 1 LAST $LOCATION R2450
J 0
(-575 2400);
DISPLAY 0.808511 (-575 2400);
FORCEPROP 1 LASTPIN (-425 2400) $PN 1
J 0
(-413 2412);
DISPLAY 0.787234 (-413 2412);
FORCEPROP 1 LASTPIN (-225 2400) $PN 2
J 0
(-263 2412);
DISPLAY 0.787234 (-263 2412);
FORCEPROP 1 LAST PACK_TYPE 0402LF
J 0
(25 2400);
DISPLAY 0.638298 (25 2400);
DISPLAY INVISIBLE (25 2400);
FORCEPROP 1 LAST WATTAGE 1/16W
J 2
(-125 2500);
DISPLAY 0.638298 (-125 2500);
DISPLAY INVISIBLE (-125 2500);
FORCEPROP 2 LAST CDS_LIB pure_quanta
J 0
(-325 2400);
DISPLAY INVISIBLE (-325 2400);
FORCEPROP 1 LAST PATH I207
J 0
(-375 2550);
DISPLAY 0.978723 (-375 2550);
PAINT WHITE (-375 2550);
DISPLAY INVISIBLE (-375 2550);
FORCEPROP 0 LAST CDS_LOCATION R2450
J 0
(-575 2450);
DISPLAY 1.021277 (-575 2450);
DISPLAY INVISIBLE (-575 2450);
FORCEPROP 0 LAST $SEC 1
J 0
(-575 2450);
DISPLAY 0.680851 (-575 2450);
PAINT MONO (-575 2450);
DISPLAY INVISIBLE (-575 2450);
FORCEPROP 0 LAST CDS_SEC 1
J 0
(-575 2450);
DISPLAY 1.021277 (-575 2450);
DISPLAY INVISIBLE (-575 2450);
FORCEADD OFFPAGE..2
(1325 1850);
FORCEPROP 2 LAST $XR1 284 
J 0
(1634 1850);
DISPLAY 0.638298 (1634 1850);
PAINT MONO (1634 1850);
FORCEPROP 2 LAST $XR0 266 
J 0
(1514 1850);
DISPLAY 0.638298 (1514 1850);
PAINT MONO (1514 1850);
FORCEPROP 2 LAST PATH I208
J 0
(1675 1900);
DISPLAY 1.021277 (1675 1900);
DISPLAY INVISIBLE (1675 1900);
FORCEPROP 1 LAST COMMENT_BODY TRUE
J 0
(1280 1755);
DISPLAY 1.170213 (1280 1755);
PAINT GREEN (1280 1755);
DISPLAY INVISIBLE (1280 1755);
FORCEPROP 1 LAST OFFPAGE TRUE
J 0
(1650 1725);
DISPLAY 1.170213 (1650 1725);
PAINT GREEN (1650 1725);
DISPLAY INVISIBLE (1650 1725);
FORCEPROP 2 LAST CDS_LIB standard
J 0
(1325 1850);
PAINT MONO (1325 1850);
DISPLAY INVISIBLE (1325 1850);
FORCEADD OFFPAGE..3
(1325 1800);
FORCEPROP 2 LAST $XR1 284 
J 0
(1659 1800);
DISPLAY 0.638298 (1659 1800);
PAINT MONO (1659 1800);
FORCEPROP 2 LAST $XR0 266 
J 0
(1539 1800);
DISPLAY 0.638298 (1539 1800);
PAINT MONO (1539 1800);
FORCEPROP 2 LAST PATH I209
J 0
(1725 1850);
DISPLAY 1.021277 (1725 1850);
DISPLAY INVISIBLE (1725 1850);
FORCEPROP 2 LAST CDS_LIB standard
J 0
(1325 1800);
PAINT MONO (1325 1800);
DISPLAY INVISIBLE (1325 1800);
FORCEPROP 1 LAST COMMENT_BODY TRUE
J 0
(1275 1700);
DISPLAY 0.872340 (1275 1700);
PAINT GREEN (1275 1700);
DISPLAY INVISIBLE (1275 1700);
FORCEPROP 1 LAST OFFPAGE TRUE
J 0
(1650 1675);
DISPLAY 0.872340 (1650 1675);
DISPLAY INVISIBLE (1650 1675);
FORCEADD OFFPAGE..3
(1325 5125);
FORCEPROP 2 LAST $XR0 237 
J 0
(1539 5125);
DISPLAY 0.638298 (1539 5125);
PAINT MONO (1539 5125);
FORCEPROP 2 LAST CDS_LIB standard
J 0
(1325 5125);
PAINT MONO (1325 5125);
DISPLAY INVISIBLE (1325 5125);
FORCEPROP 1 LAST OFFPAGE TRUE
J 0
(1650 5000);
DISPLAY 0.872340 (1650 5000);
PAINT GREEN (1650 5000);
DISPLAY INVISIBLE (1650 5000);
FORCEPROP 1 LAST COMMENT_BODY TRUE
J 0
(1275 5025);
DISPLAY 0.872340 (1275 5025);
PAINT GREEN (1275 5025);
DISPLAY INVISIBLE (1275 5025);
FORCEPROP 2 LAST PATH I21
J 0
(1550 5175);
DISPLAY 1.021277 (1550 5175);
DISPLAY INVISIBLE (1550 5175);
FORCEADD OFFPAGE..3
(1325 2075);
FORCEPROP 2 LAST $XR1 278 
J 0
(1659 2075);
DISPLAY 0.638298 (1659 2075);
PAINT MONO (1659 2075);
FORCEPROP 2 LAST $XR0 274 
J 0
(1539 2075);
DISPLAY 0.638298 (1539 2075);
PAINT MONO (1539 2075);
FORCEPROP 1 LAST OFFPAGE TRUE
J 0
(1650 1950);
DISPLAY 0.872340 (1650 1950);
DISPLAY INVISIBLE (1650 1950);
FORCEPROP 1 LAST COMMENT_BODY TRUE
J 0
(1275 1975);
DISPLAY 0.872340 (1275 1975);
PAINT GREEN (1275 1975);
DISPLAY INVISIBLE (1275 1975);
FORCEPROP 2 LAST CDS_LIB standard
J 0
(1325 2075);
PAINT MONO (1325 2075);
DISPLAY INVISIBLE (1325 2075);
FORCEPROP 2 LAST PATH I210
J 0
(2450 2125);
DISPLAY 1.021277 (2450 2125);
DISPLAY INVISIBLE (2450 2125);
FORCEADD OFFPAGE..2
(1325 2125);
FORCEPROP 2 LAST $XR1 278 
J 0
(1634 2125);
DISPLAY 0.638298 (1634 2125);
PAINT MONO (1634 2125);
FORCEPROP 2 LAST $XR0 274 
J 0
(1514 2125);
DISPLAY 0.638298 (1514 2125);
PAINT MONO (1514 2125);
FORCEPROP 2 LAST CDS_LIB standard
J 0
(1325 2125);
PAINT MONO (1325 2125);
DISPLAY INVISIBLE (1325 2125);
FORCEPROP 1 LAST OFFPAGE TRUE
J 0
(1650 2000);
DISPLAY 1.170213 (1650 2000);
PAINT GREEN (1650 2000);
DISPLAY INVISIBLE (1650 2000);
FORCEPROP 1 LAST COMMENT_BODY TRUE
J 0
(1280 2030);
DISPLAY 1.170213 (1280 2030);
PAINT GREEN (1280 2030);
DISPLAY INVISIBLE (1280 2030);
FORCEPROP 2 LAST PATH I211
J 0
(2275 2175);
DISPLAY 1.021277 (2275 2175);
DISPLAY INVISIBLE (2275 2175);
FORCEADD OFFPAGE..1
(-2075 2125);
FORCEPROP 2 LAST $XR2 296 
J 0
(-2597 2125);
DISPLAY 0.638298 (-2597 2125);
PAINT MONO (-2597 2125);
FORCEPROP 2 LAST $XR1 292 
J 0
(-2477 2125);
DISPLAY 0.638298 (-2477 2125);
PAINT MONO (-2477 2125);
FORCEPROP 2 LAST $XR0 241 
J 0
(-2357 2125);
DISPLAY 0.638298 (-2357 2125);
PAINT MONO (-2357 2125);
FORCEPROP 2 LAST CDS_LIB standard
J 0
(-2075 2125);
PAINT MONO (-2075 2125);
DISPLAY INVISIBLE (-2075 2125);
FORCEPROP 1 LAST OFFPAGE TRUE
J 0
(-1750 2000);
DISPLAY 0.872340 (-1750 2000);
PAINT GREEN (-1750 2000);
DISPLAY INVISIBLE (-1750 2000);
FORCEPROP 1 LAST COMMENT_BODY TRUE
J 0
(-1950 2025);
DISPLAY 0.872340 (-1950 2025);
PAINT GREEN (-1950 2025);
DISPLAY INVISIBLE (-1950 2025);
FORCEPROP 2 LAST PATH I214
J 0
(-2375 2175);
DISPLAY 1.021277 (-2375 2175);
DISPLAY INVISIBLE (-2375 2175);
FORCEADD OFFPAGE..3
R 2
(-2075 2075);
FORCEPROP 2 LAST $XR2 296 
J 0
(-2595 2075);
DISPLAY 0.638298 (-2595 2075);
PAINT MONO (-2595 2075);
FORCEPROP 2 LAST $XR1 292 
J 0
(-2475 2075);
DISPLAY 0.638298 (-2475 2075);
PAINT MONO (-2475 2075);
FORCEPROP 2 LAST $XR0 241 
J 0
(-2355 2075);
DISPLAY 0.638298 (-2355 2075);
PAINT MONO (-2355 2075);
FORCEPROP 2 LAST CDS_LIB standard
J 0
(-2075 2075);
PAINT MONO (-2075 2075);
DISPLAY INVISIBLE (-2075 2075);
FORCEPROP 1 LAST COMMENT_BODY TRUE
J 2
(-2025 1975);
DISPLAY 0.872340 (-2025 1975);
PAINT GREEN (-2025 1975);
DISPLAY INVISIBLE (-2025 1975);
FORCEPROP 1 LAST OFFPAGE TRUE
J 2
(-2400 1950);
DISPLAY 0.872340 (-2400 1950);
DISPLAY INVISIBLE (-2400 1950);
FORCEPROP 2 LAST PATH I215
J 0
(-2400 2125);
DISPLAY 1.021277 (-2400 2125);
DISPLAY INVISIBLE (-2400 2125);
FORCEADD Q_RES..1
(-350 1800);
FORCEPROP 1 LAST PART_NUMBER CS03322FB03
J 0
(-475 1850);
DISPLAY 0.638298 (-475 1850);
DISPLAY INVISIBLE (-475 1850);
FORCEPROP 1 LAST VALUE 33.2
J 2
(-150 1800);
DISPLAY 0.510638 (-150 1800);
FORCEPROP 1 LAST TOLERANCE 1%
J 0
(-125 1800);
DISPLAY 0.510638 (-125 1800);
FORCEPROP 1 LAST MATERIAL CHIP
J 0
(-50 1800);
DISPLAY 0.510638 (-50 1800);
FORCEPROP 1 LAST $LOCATION R2456
J 0
(-600 1800);
DISPLAY 0.808511 (-600 1800);
FORCEPROP 1 LASTPIN (-450 1800) $PN 1
J 0
(-438 1812);
DISPLAY 0.787234 (-438 1812);
PAINT MONO (-438 1812);
FORCEPROP 1 LASTPIN (-250 1800) $PN 2
J 0
(-288 1812);
DISPLAY 0.787234 (-288 1812);
PAINT MONO (-288 1812);
FORCEPROP 1 LAST PACK_TYPE 0402LF
J 0
(0 1800);
DISPLAY 0.638298 (0 1800);
DISPLAY INVISIBLE (0 1800);
FORCEPROP 1 LAST WATTAGE 1/16W
J 2
(-150 1900);
DISPLAY 0.638298 (-150 1900);
DISPLAY INVISIBLE (-150 1900);
FORCEPROP 1 LAST PATH I216
J 0
(-400 1950);
DISPLAY 0.978723 (-400 1950);
PAINT WHITE (-400 1950);
DISPLAY INVISIBLE (-400 1950);
FORCEPROP 2 LAST CDS_LIB pure_quanta
J 0
(-350 1800);
DISPLAY INVISIBLE (-350 1800);
FORCEPROP 0 LAST CDS_LOCATION R2456
J 0
(-600 1850);
DISPLAY 1.021277 (-600 1850);
DISPLAY INVISIBLE (-600 1850);
FORCEPROP 0 LAST $SEC 1
J 0
(-600 1850);
DISPLAY 0.680851 (-600 1850);
PAINT MONO (-600 1850);
DISPLAY INVISIBLE (-600 1850);
FORCEPROP 0 LAST CDS_SEC 1
J 0
(-600 1850);
DISPLAY 1.021277 (-600 1850);
DISPLAY INVISIBLE (-600 1850);
FORCEADD Q_RES..1
(-350 1850);
FORCEPROP 1 LAST PART_NUMBER CS03322FB03
J 0
(-475 1925);
DISPLAY 0.510638 (-475 1925);
DISPLAY INVISIBLE (-475 1925);
FORCEPROP 1 LAST VALUE 33.2
J 2
(-150 1850);
DISPLAY 0.510638 (-150 1850);
FORCEPROP 1 LAST TOLERANCE 1%
J 0
(-125 1850);
DISPLAY 0.510638 (-125 1850);
FORCEPROP 1 LAST PACK_TYPE 0402LF
J 0
(-475 1975);
DISPLAY 0.510638 (-475 1975);
FORCEPROP 1 LAST WATTAGE 1/16W
J 2
(-175 1975);
DISPLAY 0.510638 (-175 1975);
FORCEPROP 1 LAST MATERIAL CHIP
J 0
(-50 1850);
DISPLAY 0.510638 (-50 1850);
FORCEPROP 1 LAST $LOCATION R2455
J 0
(-600 1850);
DISPLAY 0.808511 (-600 1850);
FORCEPROP 1 LASTPIN (-450 1850) $PN 1
J 0
(-438 1862);
DISPLAY 0.787234 (-438 1862);
PAINT MONO (-438 1862);
FORCEPROP 1 LASTPIN (-250 1850) $PN 2
J 0
(-288 1862);
DISPLAY 0.787234 (-288 1862);
PAINT MONO (-288 1862);
FORCEPROP 1 LAST PATH I217
J 0
(-400 2000);
DISPLAY 0.978723 (-400 2000);
PAINT WHITE (-400 2000);
DISPLAY INVISIBLE (-400 2000);
FORCEPROP 2 LAST CDS_LIB pure_quanta
J 0
(-350 1850);
DISPLAY INVISIBLE (-350 1850);
FORCEPROP 0 LAST CDS_LOCATION R2455
J 0
(-175 2000);
DISPLAY 1.021277 (-175 2000);
DISPLAY INVISIBLE (-175 2000);
FORCEPROP 0 LAST $SEC 1
J 0
(-175 2000);
DISPLAY 0.680851 (-175 2000);
PAINT MONO (-175 2000);
DISPLAY INVISIBLE (-175 2000);
FORCEPROP 0 LAST CDS_SEC 1
J 0
(-175 2000);
DISPLAY 1.021277 (-175 2000);
DISPLAY INVISIBLE (-175 2000);
FORCEADD Q_RES..1
(-350 2075);
FORCEPROP 1 LAST PART_NUMBER CS03322FB03
J 0
(-475 2125);
DISPLAY 0.638298 (-475 2125);
DISPLAY INVISIBLE (-475 2125);
FORCEPROP 1 LAST TOLERANCE 1%
J 0
(-125 2075);
DISPLAY 0.510638 (-125 2075);
FORCEPROP 1 LAST MATERIAL CHIP
J 0
(-50 2075);
DISPLAY 0.510638 (-50 2075);
FORCEPROP 1 LAST VALUE 33.2
J 2
(-150 2075);
DISPLAY 0.510638 (-150 2075);
FORCEPROP 1 LAST $LOCATION R2454
J 0
(-600 2075);
DISPLAY 0.808511 (-600 2075);
FORCEPROP 1 LASTPIN (-450 2075) $PN 1
J 0
(-438 2087);
DISPLAY 0.787234 (-438 2087);
PAINT MONO (-438 2087);
FORCEPROP 1 LASTPIN (-250 2075) $PN 2
J 0
(-288 2087);
DISPLAY 0.787234 (-288 2087);
PAINT MONO (-288 2087);
FORCEPROP 1 LAST WATTAGE 1/16W
J 2
(-150 2175);
DISPLAY 0.638298 (-150 2175);
DISPLAY INVISIBLE (-150 2175);
FORCEPROP 1 LAST PACK_TYPE 0402LF
J 0
(0 2075);
DISPLAY 0.638298 (0 2075);
DISPLAY INVISIBLE (0 2075);
FORCEPROP 2 LAST CDS_LIB pure_quanta
J 0
(-350 2075);
DISPLAY INVISIBLE (-350 2075);
FORCEPROP 1 LAST PATH I218
J 0
(-400 2225);
DISPLAY 0.978723 (-400 2225);
PAINT WHITE (-400 2225);
DISPLAY INVISIBLE (-400 2225);
FORCEPROP 0 LAST CDS_LOCATION R2454
J 0
(-600 2125);
DISPLAY 1.021277 (-600 2125);
DISPLAY INVISIBLE (-600 2125);
FORCEPROP 0 LAST $SEC 1
J 0
(-600 2125);
DISPLAY 0.680851 (-600 2125);
PAINT MONO (-600 2125);
DISPLAY INVISIBLE (-600 2125);
FORCEPROP 0 LAST CDS_SEC 1
J 0
(-600 2125);
DISPLAY 1.021277 (-600 2125);
DISPLAY INVISIBLE (-600 2125);
FORCEADD Q_RES..1
(-350 2125);
FORCEPROP 1 LAST PART_NUMBER CS03322FB03
J 0
(-475 2200);
DISPLAY 0.510638 (-475 2200);
DISPLAY INVISIBLE (-475 2200);
FORCEPROP 1 LAST WATTAGE 1/16W
J 2
(-175 2250);
DISPLAY 0.510638 (-175 2250);
FORCEPROP 1 LAST TOLERANCE 1%
J 0
(-125 2125);
DISPLAY 0.510638 (-125 2125);
FORCEPROP 1 LAST MATERIAL CHIP
J 0
(-50 2125);
DISPLAY 0.510638 (-50 2125);
FORCEPROP 1 LAST PACK_TYPE 0402LF
J 0
(-475 2250);
DISPLAY 0.510638 (-475 2250);
FORCEPROP 1 LAST VALUE 33.2
J 2
(-150 2125);
DISPLAY 0.510638 (-150 2125);
FORCEPROP 1 LAST $LOCATION R2453
J 0
(-600 2125);
DISPLAY 0.808511 (-600 2125);
FORCEPROP 1 LASTPIN (-450 2125) $PN 1
J 0
(-438 2137);
DISPLAY 0.787234 (-438 2137);
PAINT MONO (-438 2137);
FORCEPROP 1 LASTPIN (-250 2125) $PN 2
J 0
(-288 2137);
DISPLAY 0.787234 (-288 2137);
PAINT MONO (-288 2137);
FORCEPROP 2 LAST CDS_LIB pure_quanta
J 0
(-350 2125);
DISPLAY INVISIBLE (-350 2125);
FORCEPROP 1 LAST PATH I219
J 0
(-400 2275);
DISPLAY 0.978723 (-400 2275);
PAINT WHITE (-400 2275);
DISPLAY INVISIBLE (-400 2275);
FORCEPROP 0 LAST CDS_LOCATION R2453
J 0
(-175 2275);
DISPLAY 1.021277 (-175 2275);
DISPLAY INVISIBLE (-175 2275);
FORCEPROP 0 LAST $SEC 1
J 0
(-175 2275);
DISPLAY 0.680851 (-175 2275);
PAINT MONO (-175 2275);
DISPLAY INVISIBLE (-175 2275);
FORCEPROP 0 LAST CDS_SEC 1
J 0
(-175 2275);
DISPLAY 1.021277 (-175 2275);
DISPLAY INVISIBLE (-175 2275);
FORCEADD OFFPAGE..2
(1375 4550);
FORCEPROP 2 LAST $XR0 183 
J 0
(1564 4550);
DISPLAY 0.638298 (1564 4550);
PAINT MONO (1564 4550);
FORCEPROP 2 LAST CDS_LIB standard
J 0
(1375 4550);
PAINT MONO (1375 4550);
DISPLAY INVISIBLE (1375 4550);
FORCEPROP 1 LAST COMMENT_BODY TRUE
J 0
(1330 4455);
DISPLAY 0.872340 (1330 4455);
PAINT GREEN (1330 4455);
DISPLAY INVISIBLE (1330 4455);
FORCEPROP 1 LAST OFFPAGE TRUE
J 0
(1700 4425);
DISPLAY 0.872340 (1700 4425);
PAINT GREEN (1700 4425);
DISPLAY INVISIBLE (1700 4425);
FORCEPROP 2 LAST PATH I22
J 0
(1575 4600);
DISPLAY 1.021277 (1575 4600);
DISPLAY INVISIBLE (1575 4600);
FORCEADD OFFPAGE..3
(1375 3875);
FORCEPROP 2 LAST $XR0 241 
J 0
(1589 3875);
DISPLAY 0.638298 (1589 3875);
PAINT MONO (1589 3875);
FORCEPROP 2 LAST PATH I226
J 0
(1725 3925);
DISPLAY 1.021277 (1725 3925);
DISPLAY INVISIBLE (1725 3925);
FORCEPROP 1 LAST OFFPAGE TRUE
J 0
(1700 3750);
DISPLAY 0.872340 (1700 3750);
DISPLAY INVISIBLE (1700 3750);
FORCEPROP 1 LAST COMMENT_BODY TRUE
J 0
(1325 3775);
DISPLAY 0.872340 (1325 3775);
PAINT GREEN (1325 3775);
DISPLAY INVISIBLE (1325 3775);
FORCEPROP 2 LAST CDS_LIB standard
J 0
(1375 3875);
PAINT MONO (1375 3875);
DISPLAY INVISIBLE (1375 3875);
FORCEADD OFFPAGE..2
(1375 3925);
FORCEPROP 2 LAST $XR0 241 
J 0
(1564 3925);
DISPLAY 0.638298 (1564 3925);
PAINT MONO (1564 3925);
FORCEPROP 2 LAST PATH I227
J 0
(1700 3975);
DISPLAY 1.021277 (1700 3975);
DISPLAY INVISIBLE (1700 3975);
FORCEPROP 2 LAST CDS_LIB standard
J 0
(1375 3925);
PAINT MONO (1375 3925);
DISPLAY INVISIBLE (1375 3925);
FORCEPROP 1 LAST OFFPAGE TRUE
J 0
(1700 3800);
DISPLAY 1.170213 (1700 3800);
PAINT GREEN (1700 3800);
DISPLAY INVISIBLE (1700 3800);
FORCEPROP 1 LAST COMMENT_BODY TRUE
J 0
(1330 3830);
DISPLAY 1.170213 (1330 3830);
PAINT GREEN (1330 3830);
DISPLAY INVISIBLE (1330 3830);
FORCEADD Q_RES..1
(-300 3925);
FORCEPROP 1 LAST PART_NUMBER CS03322FB03
J 0
(-425 4000);
DISPLAY 0.510638 (-425 4000);
DISPLAY INVISIBLE (-425 4000);
FORCEPROP 1 LAST WATTAGE 1/16W
J 2
(-125 4050);
DISPLAY 0.510638 (-125 4050);
FORCEPROP 1 LAST PACK_TYPE 0402LF
J 0
(-425 4050);
DISPLAY 0.510638 (-425 4050);
FORCEPROP 1 LAST MATERIAL CHIP
J 0
(0 3925);
DISPLAY 0.510638 (0 3925);
FORCEPROP 1 LAST VALUE 33.2
J 2
(-100 3925);
DISPLAY 0.510638 (-100 3925);
FORCEPROP 1 LAST TOLERANCE 1%
J 0
(-75 3925);
DISPLAY 0.510638 (-75 3925);
FORCEPROP 1 LAST $LOCATION R2995
J 0
(-550 3925);
DISPLAY 0.808511 (-550 3925);
FORCEPROP 1 LASTPIN (-400 3925) $PN 1
J 0
(-388 3937);
DISPLAY 0.787234 (-388 3937);
FORCEPROP 1 LASTPIN (-200 3925) $PN 2
J 0
(-238 3937);
DISPLAY 0.787234 (-238 3937);
FORCEPROP 1 LAST PATH I228
J 0
(-350 4075);
DISPLAY 0.978723 (-350 4075);
PAINT WHITE (-350 4075);
DISPLAY INVISIBLE (-350 4075);
FORCEPROP 2 LAST CDS_LIB pure_quanta
J 0
(-300 3925);
DISPLAY INVISIBLE (-300 3925);
FORCEPROP 0 LAST CDS_LOCATION R2995
J 0
(-125 4075);
DISPLAY 1.021277 (-125 4075);
DISPLAY INVISIBLE (-125 4075);
FORCEPROP 0 LAST $SEC 1
J 0
(-125 4075);
DISPLAY 0.680851 (-125 4075);
PAINT MONO (-125 4075);
DISPLAY INVISIBLE (-125 4075);
FORCEPROP 0 LAST CDS_SEC 1
J 0
(-125 4075);
DISPLAY 1.021277 (-125 4075);
DISPLAY INVISIBLE (-125 4075);
FORCEADD Q_RES..1
(-300 3875);
FORCEPROP 1 LAST PART_NUMBER CS03322FB03
J 0
(-425 3925);
DISPLAY 0.638298 (-425 3925);
DISPLAY INVISIBLE (-425 3925);
FORCEPROP 1 LAST TOLERANCE 1%
J 0
(-75 3875);
DISPLAY 0.510638 (-75 3875);
FORCEPROP 1 LAST VALUE 33.2
J 2
(-100 3875);
DISPLAY 0.510638 (-100 3875);
FORCEPROP 1 LAST MATERIAL CHIP
J 0
(0 3875);
DISPLAY 0.510638 (0 3875);
FORCEPROP 1 LAST $LOCATION R2996
J 0
(-550 3875);
DISPLAY 0.808511 (-550 3875);
FORCEPROP 1 LASTPIN (-400 3875) $PN 1
J 0
(-388 3887);
DISPLAY 0.787234 (-388 3887);
FORCEPROP 1 LASTPIN (-200 3875) $PN 2
J 0
(-238 3887);
DISPLAY 0.787234 (-238 3887);
FORCEPROP 1 LAST PATH I229
J 0
(-350 4025);
DISPLAY 0.978723 (-350 4025);
PAINT WHITE (-350 4025);
DISPLAY INVISIBLE (-350 4025);
FORCEPROP 1 LAST PACK_TYPE 0402LF
J 0
(50 3875);
DISPLAY 0.638298 (50 3875);
DISPLAY INVISIBLE (50 3875);
FORCEPROP 1 LAST WATTAGE 1/16W
J 2
(-100 3975);
DISPLAY 0.638298 (-100 3975);
DISPLAY INVISIBLE (-100 3975);
FORCEPROP 2 LAST CDS_LIB pure_quanta
J 0
(-300 3875);
DISPLAY INVISIBLE (-300 3875);
FORCEPROP 0 LAST CDS_LOCATION R2996
J 0
(-550 3925);
DISPLAY 1.021277 (-550 3925);
DISPLAY INVISIBLE (-550 3925);
FORCEPROP 0 LAST $SEC 1
J 0
(-550 3925);
DISPLAY 0.680851 (-550 3925);
PAINT MONO (-550 3925);
DISPLAY INVISIBLE (-550 3925);
FORCEPROP 0 LAST CDS_SEC 1
J 0
(-550 3925);
DISPLAY 1.021277 (-550 3925);
DISPLAY INVISIBLE (-550 3925);
FORCEADD OFFPAGE..3
(1375 4500);
FORCEPROP 2 LAST $XR0 183 
J 0
(1589 4500);
DISPLAY 0.638298 (1589 4500);
PAINT MONO (1589 4500);
FORCEPROP 2 LAST CDS_LIB standard
J 0
(1375 4500);
PAINT MONO (1375 4500);
DISPLAY INVISIBLE (1375 4500);
FORCEPROP 1 LAST OFFPAGE TRUE
J 0
(1700 4375);
DISPLAY 0.872340 (1700 4375);
PAINT GREEN (1700 4375);
DISPLAY INVISIBLE (1700 4375);
FORCEPROP 1 LAST COMMENT_BODY TRUE
J 0
(1325 4400);
DISPLAY 0.872340 (1325 4400);
PAINT GREEN (1325 4400);
DISPLAY INVISIBLE (1325 4400);
FORCEPROP 2 LAST PATH I23
J 0
(1600 4550);
DISPLAY 1.021277 (1600 4550);
DISPLAY INVISIBLE (1600 4550);
FORCEADD Q_RES..1
(5000 3650);
FORCEPROP 1 LAST PART_NUMBER CS22202JB07
J 0
(4900 3700);
DISPLAY 0.510638 (4900 3700);
DISPLAY INVISIBLE (4900 3700);
FORCEPROP 1 LAST TOLERANCE 5%
J 0
(5225 3650);
DISPLAY 0.510638 (5225 3650);
FORCEPROP 1 LAST MATERIAL EMPTY
J 0
(5300 3650);
DISPLAY 0.510638 (5300 3650);
PAINT RED (5300 3650);
FORCEPROP 1 LAST VALUE 2.2K
J 2
(5225 3650);
DISPLAY 0.510638 (5225 3650);
FORCEPROP 1 LAST $LOCATION R3004
J 0
(4750 3650);
DISPLAY 0.787234 (4750 3650);
FORCEPROP 1 LASTPIN (4900 3650) $PN 1
J 0
(4912 3662);
DISPLAY 0.787234 (4912 3662);
PAINT MONO (4912 3662);
FORCEPROP 1 LASTPIN (5100 3650) $PN 2
J 0
(5062 3662);
DISPLAY 0.787234 (5062 3662);
PAINT MONO (5062 3662);
FORCEPROP 1 LAST PATH I230
J 0
(4950 3800);
DISPLAY 0.978723 (4950 3800);
PAINT WHITE (4950 3800);
DISPLAY INVISIBLE (4950 3800);
FORCEPROP 1 LAST PACK_TYPE 0402LF
J 0
(4900 3750);
DISPLAY 0.510638 (4900 3750);
DISPLAY INVISIBLE (4900 3750);
FORCEPROP 1 LAST WATTAGE 1/16W
J 2
(5200 3750);
DISPLAY 0.510638 (5200 3750);
DISPLAY INVISIBLE (5200 3750);
FORCEPROP 2 LAST CDS_LIB pure_quanta
J 0
(5000 3650);
DISPLAY INVISIBLE (5000 3650);
FORCEPROP 0 LAST CDS_LOCATION R3004
J 0
(4750 3700);
DISPLAY 1.021277 (4750 3700);
DISPLAY INVISIBLE (4750 3700);
FORCEPROP 0 LAST $SEC 1
J 0
(4750 3700);
DISPLAY 0.680851 (4750 3700);
PAINT MONO (4750 3700);
DISPLAY INVISIBLE (4750 3700);
FORCEPROP 0 LAST CDS_SEC 1
J 0
(4750 3700);
DISPLAY 1.021277 (4750 3700);
DISPLAY INVISIBLE (4750 3700);
FORCEADD Q_RES..1
(5000 3700);
FORCEPROP 1 LAST PART_NUMBER CS22202JB07
J 0
(4850 3775);
DISPLAY 0.510638 (4850 3775);
DISPLAY INVISIBLE (4850 3775);
FORCEPROP 1 LAST WATTAGE 1/16W
J 2
(5150 3825);
DISPLAY 0.510638 (5150 3825);
FORCEPROP 1 LAST PACK_TYPE 0402LF
J 0
(4850 3825);
DISPLAY 0.510638 (4850 3825);
FORCEPROP 1 LAST TOLERANCE 5%
J 0
(5225 3700);
DISPLAY 0.510638 (5225 3700);
FORCEPROP 1 LAST MATERIAL EMPTY
J 0
(5300 3700);
DISPLAY 0.510638 (5300 3700);
PAINT RED (5300 3700);
FORCEPROP 1 LAST VALUE 2.2K
J 2
(5225 3700);
DISPLAY 0.510638 (5225 3700);
FORCEPROP 1 LAST $LOCATION R2999
J 0
(4750 3700);
DISPLAY 0.787234 (4750 3700);
FORCEPROP 1 LASTPIN (4900 3700) $PN 1
J 0
(4912 3712);
DISPLAY 0.787234 (4912 3712);
PAINT MONO (4912 3712);
FORCEPROP 1 LASTPIN (5100 3700) $PN 2
J 0
(5062 3712);
DISPLAY 0.787234 (5062 3712);
PAINT MONO (5062 3712);
FORCEPROP 1 LAST PATH I231
J 0
(4950 3850);
DISPLAY 0.978723 (4950 3850);
PAINT WHITE (4950 3850);
DISPLAY INVISIBLE (4950 3850);
FORCEPROP 2 LAST CDS_LIB pure_quanta
J 0
(5000 3700);
DISPLAY INVISIBLE (5000 3700);
FORCEPROP 0 LAST CDS_LOCATION R2999
J 0
(5150 3850);
DISPLAY 1.021277 (5150 3850);
DISPLAY INVISIBLE (5150 3850);
FORCEPROP 0 LAST $SEC 1
J 0
(5150 3850);
DISPLAY 0.680851 (5150 3850);
PAINT MONO (5150 3850);
DISPLAY INVISIBLE (5150 3850);
FORCEPROP 0 LAST CDS_SEC 1
J 0
(5150 3850);
DISPLAY 1.021277 (5150 3850);
DISPLAY INVISIBLE (5150 3850);
FORCEADD OFFPAGE..5
(3500 3700);
FORCEPROP 2 LAST $XR1 240 
J 0
(3095 3700);
DISPLAY 0.638298 (3095 3700);
PAINT MONO (3095 3700);
FORCEPROP 2 LAST $XR0 234 
J 0
(3215 3700);
DISPLAY 0.638298 (3215 3700);
PAINT MONO (3215 3700);
FORCEPROP 1 LAST COMMENT_BODY TRUE
J 0
(3600 3625);
DISPLAY 0.872340 (3600 3625);
PAINT PEACH (3600 3625);
DISPLAY INVISIBLE (3600 3625);
FORCEPROP 1 LAST OFFPAGE TRUE
J 0
(3825 3575);
DISPLAY 0.872340 (3825 3575);
PAINT GREEN (3825 3575);
DISPLAY INVISIBLE (3825 3575);
FORCEPROP 2 LAST CDS_LIB standard
J 0
(3500 3700);
DISPLAY INVISIBLE (3500 3700);
FORCEPROP 2 LAST PATH I232
J 0
(3225 3750);
DISPLAY 1.021277 (3225 3750);
DISPLAY INVISIBLE (3225 3750);
FORCEADD OFFPAGE..5
(3500 3650);
FORCEPROP 2 LAST $XR1 234 
J 0
(3095 3650);
DISPLAY 0.638298 (3095 3650);
PAINT MONO (3095 3650);
FORCEPROP 2 LAST $XR0 240 
J 0
(3215 3650);
DISPLAY 0.638298 (3215 3650);
PAINT MONO (3215 3650);
FORCEPROP 1 LAST COMMENT_BODY TRUE
J 0
(3600 3575);
DISPLAY 0.872340 (3600 3575);
PAINT PEACH (3600 3575);
DISPLAY INVISIBLE (3600 3575);
FORCEPROP 1 LAST OFFPAGE TRUE
J 0
(3825 3525);
DISPLAY 0.872340 (3825 3525);
PAINT GREEN (3825 3525);
DISPLAY INVISIBLE (3825 3525);
FORCEPROP 2 LAST CDS_LIB standard
J 0
(3500 3650);
DISPLAY INVISIBLE (3500 3650);
FORCEPROP 2 LAST PATH I233
J 0
(3225 3700);
DISPLAY 1.021277 (3225 3700);
DISPLAY INVISIBLE (3225 3700);
FORCEADD Q_RES..1
(-325 3000);
FORCEPROP 1 LAST PART_NUMBER CS03322FB03
J 0
(-450 3050);
DISPLAY 0.638298 (-450 3050);
DISPLAY INVISIBLE (-450 3050);
FORCEPROP 1 LAST MATERIAL CHIP
J 0
(-25 3000);
DISPLAY 0.510638 (-25 3000);
FORCEPROP 1 LAST TOLERANCE 1%
J 0
(-100 3000);
DISPLAY 0.510638 (-100 3000);
FORCEPROP 1 LAST VALUE 33.2
J 2
(-125 3000);
DISPLAY 0.510638 (-125 3000);
FORCEPROP 1 LAST $LOCATION R3061
J 0
(-600 3000);
DISPLAY 0.787234 (-600 3000);
FORCEPROP 1 LASTPIN (-425 3000) $PN 1
J 0
(-413 3012);
DISPLAY 0.787234 (-413 3012);
FORCEPROP 1 LASTPIN (-225 3000) $PN 2
J 0
(-263 3012);
DISPLAY 0.787234 (-263 3012);
FORCEPROP 1 LAST PACK_TYPE 0402LF
J 0
(25 3000);
DISPLAY 0.638298 (25 3000);
DISPLAY INVISIBLE (25 3000);
FORCEPROP 1 LAST WATTAGE 1/16W
J 2
(-125 3100);
DISPLAY 0.638298 (-125 3100);
DISPLAY INVISIBLE (-125 3100);
FORCEPROP 2 LAST CDS_LIB pure_quanta
J 0
(-325 3000);
PAINT MONO (-325 3000);
DISPLAY INVISIBLE (-325 3000);
FORCEPROP 1 LAST PATH I234
J 0
(-375 3150);
DISPLAY 0.978723 (-375 3150);
PAINT WHITE (-375 3150);
DISPLAY INVISIBLE (-375 3150);
FORCEPROP 2 LAST CDS_LOCATION R3061
J 0
(-375 3200);
DISPLAY 1.021277 (-375 3200);
DISPLAY INVISIBLE (-375 3200);
FORCEPROP 2 LAST $SEC 1
J 0
(-375 3200);
DISPLAY 0.680851 (-375 3200);
PAINT MONO (-375 3200);
DISPLAY INVISIBLE (-375 3200);
FORCEPROP 2 LAST CDS_SEC 1
J 0
(-375 3200);
DISPLAY 1.021277 (-375 3200);
DISPLAY INVISIBLE (-375 3200);
FORCEADD OFFPAGE..2
(1350 3050);
FORCEPROP 2 LAST $XR0 228 
J 0
(1539 3050);
DISPLAY 0.638298 (1539 3050);
PAINT MONO (1539 3050);
FORCEPROP 1 LAST OFFPAGE TRUE
J 0
(1675 2925);
DISPLAY 0.872340 (1675 2925);
PAINT GREEN (1675 2925);
DISPLAY INVISIBLE (1675 2925);
FORCEPROP 1 LAST COMMENT_BODY TRUE
J 0
(1305 2955);
DISPLAY 0.872340 (1305 2955);
PAINT GREEN (1305 2955);
DISPLAY INVISIBLE (1305 2955);
FORCEPROP 2 LAST CDS_LIB standard
J 0
(1350 3050);
PAINT MONO (1350 3050);
DISPLAY INVISIBLE (1350 3050);
FORCEPROP 2 LAST PATH I235
J 0
(1550 3100);
DISPLAY 1.021277 (1550 3100);
DISPLAY INVISIBLE (1550 3100);
FORCEADD OFFPAGE..3
(1350 3000);
FORCEPROP 2 LAST $XR0 228 
J 0
(1564 3000);
DISPLAY 0.638298 (1564 3000);
PAINT MONO (1564 3000);
FORCEPROP 1 LAST COMMENT_BODY TRUE
J 0
(1300 2900);
DISPLAY 0.872340 (1300 2900);
PAINT GREEN (1300 2900);
DISPLAY INVISIBLE (1300 2900);
FORCEPROP 1 LAST OFFPAGE TRUE
J 0
(1675 2875);
DISPLAY 0.872340 (1675 2875);
PAINT GREEN (1675 2875);
DISPLAY INVISIBLE (1675 2875);
FORCEPROP 2 LAST CDS_LIB standard
J 0
(1350 3000);
PAINT MONO (1350 3000);
DISPLAY INVISIBLE (1350 3000);
FORCEPROP 2 LAST PATH I236
J 0
(1575 3050);
DISPLAY 1.021277 (1575 3050);
DISPLAY INVISIBLE (1575 3050);
FORCEADD Q_RES..1
(-325 3050);
FORCEPROP 1 LAST PART_NUMBER CS03322FB03
J 0
(-450 3125);
DISPLAY 0.510638 (-450 3125);
DISPLAY INVISIBLE (-450 3125);
FORCEPROP 1 LAST MATERIAL CHIP
J 0
(-25 3050);
DISPLAY 0.510638 (-25 3050);
FORCEPROP 1 LAST VALUE 33.2
J 2
(-125 3050);
DISPLAY 0.510638 (-125 3050);
FORCEPROP 1 LAST PACK_TYPE 0402LF
J 0
(-450 3175);
DISPLAY 0.510638 (-450 3175);
FORCEPROP 1 LAST WATTAGE 1/16W
J 2
(-125 3175);
DISPLAY 0.510638 (-125 3175);
FORCEPROP 1 LAST TOLERANCE 1%
J 0
(-100 3050);
DISPLAY 0.510638 (-100 3050);
FORCEPROP 1 LAST $LOCATION R3060
J 0
(-600 3050);
DISPLAY 0.787234 (-600 3050);
FORCEPROP 1 LASTPIN (-425 3050) $PN 1
J 0
(-413 3062);
DISPLAY 0.787234 (-413 3062);
FORCEPROP 1 LASTPIN (-225 3050) $PN 2
J 0
(-263 3062);
DISPLAY 0.787234 (-263 3062);
FORCEPROP 2 LAST CDS_LIB pure_quanta
J 0
(-325 3050);
PAINT MONO (-325 3050);
DISPLAY INVISIBLE (-325 3050);
FORCEPROP 1 LAST PATH I237
J 0
(-375 3200);
DISPLAY 0.978723 (-375 3200);
PAINT WHITE (-375 3200);
DISPLAY INVISIBLE (-375 3200);
FORCEPROP 2 LAST CDS_LOCATION R3060
J 0
(-375 3250);
DISPLAY 1.021277 (-375 3250);
DISPLAY INVISIBLE (-375 3250);
FORCEPROP 2 LAST $SEC 1
J 0
(-375 3250);
DISPLAY 0.680851 (-375 3250);
PAINT MONO (-375 3250);
DISPLAY INVISIBLE (-375 3250);
FORCEPROP 2 LAST CDS_SEC 1
J 0
(-375 3250);
DISPLAY 1.021277 (-375 3250);
DISPLAY INVISIBLE (-375 3250);
FORCEADD OFFPAGE..1
(-2050 3050);
FORCEPROP 2 LAST $XR2 183 
J 0
(-2542 3050);
DISPLAY 0.638298 (-2542 3050);
PAINT MONO (-2542 3050);
FORCEPROP 2 LAST $XR1 241 
J 0
(-2422 3050);
DISPLAY 0.638298 (-2422 3050);
PAINT MONO (-2422 3050);
FORCEPROP 2 LAST $XR0 240 
J 0
(-2302 3050);
DISPLAY 0.638298 (-2302 3050);
PAINT MONO (-2302 3050);
FORCEPROP 2 LAST CDS_LIB standard
J 0
(-2050 3050);
PAINT MONO (-2050 3050);
DISPLAY INVISIBLE (-2050 3050);
FORCEPROP 1 LAST COMMENT_BODY TRUE
J 0
(-1925 2950);
DISPLAY 0.872340 (-1925 2950);
PAINT GREEN (-1925 2950);
DISPLAY INVISIBLE (-1925 2950);
FORCEPROP 1 LAST OFFPAGE TRUE
J 0
(-1725 2925);
DISPLAY 0.872340 (-1725 2925);
PAINT GREEN (-1725 2925);
DISPLAY INVISIBLE (-1725 2925);
FORCEPROP 2 LAST PATH I238
J 0
(-2325 3100);
DISPLAY 1.021277 (-2325 3100);
DISPLAY INVISIBLE (-2325 3100);
FORCEADD OFFPAGE..3
R 2
(-2050 3000);
FORCEPROP 2 LAST $XR2 241 
J 0
(-2570 3000);
DISPLAY 0.638298 (-2570 3000);
PAINT MONO (-2570 3000);
FORCEPROP 2 LAST $XR1 240 
J 0
(-2450 3000);
DISPLAY 0.638298 (-2450 3000);
PAINT MONO (-2450 3000);
FORCEPROP 2 LAST $XR0 183 
J 0
(-2330 3000);
DISPLAY 0.638298 (-2330 3000);
PAINT MONO (-2330 3000);
FORCEPROP 1 LAST OFFPAGE TRUE
J 2
(-2375 2875);
DISPLAY 0.872340 (-2375 2875);
DISPLAY INVISIBLE (-2375 2875);
FORCEPROP 1 LAST COMMENT_BODY TRUE
J 2
(-2000 2900);
DISPLAY 0.872340 (-2000 2900);
PAINT GREEN (-2000 2900);
DISPLAY INVISIBLE (-2000 2900);
FORCEPROP 2 LAST CDS_LIB standard
J 0
(-2050 3000);
PAINT MONO (-2050 3000);
DISPLAY INVISIBLE (-2050 3000);
FORCEPROP 2 LAST PATH I239
J 0
(-2350 3050);
DISPLAY 1.021277 (-2350 3050);
DISPLAY INVISIBLE (-2350 3050);
FORCEADD OFFPAGE..3
(1375 4225);
FORCEPROP 2 LAST $XR0 228 
J 0
(1589 4225);
DISPLAY 0.638298 (1589 4225);
PAINT MONO (1589 4225);
FORCEPROP 1 LAST OFFPAGE TRUE
J 0
(1700 4100);
DISPLAY 0.872340 (1700 4100);
DISPLAY INVISIBLE (1700 4100);
FORCEPROP 1 LAST COMMENT_BODY TRUE
J 0
(1325 4125);
DISPLAY 0.872340 (1325 4125);
PAINT GREEN (1325 4125);
DISPLAY INVISIBLE (1325 4125);
FORCEPROP 2 LAST CDS_LIB standard
J 0
(1375 4225);
PAINT MONO (1375 4225);
DISPLAY INVISIBLE (1375 4225);
FORCEPROP 2 LAST PATH I240
J 0
(1600 4275);
DISPLAY 1.021277 (1600 4275);
DISPLAY INVISIBLE (1600 4275);
FORCEADD OFFPAGE..2
(1375 4275);
FORCEPROP 2 LAST $XR0 228 
J 0
(1564 4275);
DISPLAY 0.638298 (1564 4275);
PAINT MONO (1564 4275);
FORCEPROP 2 LAST CDS_LIB standard
J 0
(1375 4275);
PAINT MONO (1375 4275);
DISPLAY INVISIBLE (1375 4275);
FORCEPROP 1 LAST OFFPAGE TRUE
J 0
(1700 4150);
DISPLAY 1.170213 (1700 4150);
PAINT GREEN (1700 4150);
DISPLAY INVISIBLE (1700 4150);
FORCEPROP 1 LAST COMMENT_BODY TRUE
J 0
(1330 4180);
DISPLAY 1.170213 (1330 4180);
PAINT GREEN (1330 4180);
DISPLAY INVISIBLE (1330 4180);
FORCEPROP 2 LAST PATH I241
J 0
(1575 4325);
DISPLAY 1.021277 (1575 4325);
DISPLAY INVISIBLE (1575 4325);
FORCEADD Q_RES..1
(-300 4275);
FORCEPROP 1 LAST PART_NUMBER CS03322FB03
J 0
(-425 4350);
DISPLAY 0.510638 (-425 4350);
DISPLAY INVISIBLE (-425 4350);
FORCEPROP 1 LAST WATTAGE 1/16W
J 2
(-125 4400);
DISPLAY 0.510638 (-125 4400);
FORCEPROP 1 LAST VALUE 33.2
J 2
(-100 4275);
DISPLAY 0.510638 (-100 4275);
FORCEPROP 1 LAST MATERIAL CHIP
J 0
(0 4275);
DISPLAY 0.510638 (0 4275);
FORCEPROP 1 LAST TOLERANCE 1%
J 0
(-75 4275);
DISPLAY 0.510638 (-75 4275);
FORCEPROP 1 LAST PACK_TYPE 0402LF
J 0
(-425 4400);
DISPLAY 0.510638 (-425 4400);
FORCEPROP 1 LAST $LOCATION R3058
J 0
(-550 4275);
DISPLAY 0.808511 (-550 4275);
FORCEPROP 1 LASTPIN (-400 4275) $PN 1
J 0
(-388 4287);
DISPLAY 0.787234 (-388 4287);
FORCEPROP 1 LASTPIN (-200 4275) $PN 2
J 0
(-238 4287);
DISPLAY 0.787234 (-238 4287);
FORCEPROP 2 LAST CDS_LIB pure_quanta
J 0
(-300 4275);
DISPLAY INVISIBLE (-300 4275);
FORCEPROP 1 LAST PATH I242
J 0
(-350 4425);
DISPLAY 0.978723 (-350 4425);
PAINT WHITE (-350 4425);
DISPLAY INVISIBLE (-350 4425);
FORCEPROP 0 LAST CDS_LOCATION R3058
J 0
(-125 4425);
DISPLAY 1.021277 (-125 4425);
DISPLAY INVISIBLE (-125 4425);
FORCEPROP 0 LAST $SEC 1
J 0
(-125 4425);
DISPLAY 0.680851 (-125 4425);
PAINT MONO (-125 4425);
DISPLAY INVISIBLE (-125 4425);
FORCEPROP 0 LAST CDS_SEC 1
J 0
(-125 4425);
DISPLAY 1.021277 (-125 4425);
DISPLAY INVISIBLE (-125 4425);
FORCEADD Q_RES..1
(-300 4225);
FORCEPROP 1 LAST PART_NUMBER CS03322FB03
J 0
(-425 4275);
DISPLAY 0.638298 (-425 4275);
DISPLAY INVISIBLE (-425 4275);
FORCEPROP 1 LAST TOLERANCE 1%
J 0
(-75 4225);
DISPLAY 0.510638 (-75 4225);
FORCEPROP 1 LAST VALUE 33.2
J 2
(-100 4225);
DISPLAY 0.510638 (-100 4225);
FORCEPROP 1 LAST MATERIAL CHIP
J 0
(0 4225);
DISPLAY 0.510638 (0 4225);
FORCEPROP 1 LAST $LOCATION R3059
J 0
(-550 4225);
DISPLAY 0.808511 (-550 4225);
FORCEPROP 1 LASTPIN (-400 4225) $PN 1
J 0
(-388 4237);
DISPLAY 0.787234 (-388 4237);
FORCEPROP 1 LASTPIN (-200 4225) $PN 2
J 0
(-238 4237);
DISPLAY 0.787234 (-238 4237);
FORCEPROP 1 LAST PACK_TYPE 0402LF
J 0
(50 4225);
DISPLAY 0.638298 (50 4225);
DISPLAY INVISIBLE (50 4225);
FORCEPROP 1 LAST WATTAGE 1/16W
J 2
(-100 4325);
DISPLAY 0.638298 (-100 4325);
DISPLAY INVISIBLE (-100 4325);
FORCEPROP 2 LAST CDS_LIB pure_quanta
J 0
(-300 4225);
DISPLAY INVISIBLE (-300 4225);
FORCEPROP 1 LAST PATH I243
J 0
(-350 4375);
DISPLAY 0.978723 (-350 4375);
PAINT WHITE (-350 4375);
DISPLAY INVISIBLE (-350 4375);
FORCEPROP 0 LAST CDS_LOCATION R3059
J 0
(-550 4275);
DISPLAY 1.021277 (-550 4275);
DISPLAY INVISIBLE (-550 4275);
FORCEPROP 0 LAST $SEC 1
J 0
(-550 4275);
DISPLAY 0.680851 (-550 4275);
PAINT MONO (-550 4275);
DISPLAY INVISIBLE (-550 4275);
FORCEPROP 0 LAST CDS_SEC 1
J 0
(-550 4275);
DISPLAY 1.021277 (-550 4275);
DISPLAY INVISIBLE (-550 4275);
FORCEADD Q_RES..1
(5000 3250);
FORCEPROP 1 LAST PART_NUMBER CS22202JB07
J 0
(4900 3300);
DISPLAY 0.510638 (4900 3300);
DISPLAY INVISIBLE (4900 3300);
FORCEPROP 1 LAST VALUE 2.2K
J 2
(5225 3250);
DISPLAY 0.510638 (5225 3250);
FORCEPROP 1 LAST TOLERANCE 5%
J 0
(5225 3250);
DISPLAY 0.510638 (5225 3250);
FORCEPROP 1 LAST MATERIAL EMPTY
J 0
(5300 3250);
DISPLAY 0.510638 (5300 3250);
PAINT RED (5300 3250);
FORCEPROP 1 LAST $LOCATION R3227
J 0
(4750 3250);
DISPLAY 0.787234 (4750 3250);
FORCEPROP 1 LASTPIN (4900 3250) $PN 1
J 0
(4912 3262);
DISPLAY 0.787234 (4912 3262);
PAINT MONO (4912 3262);
FORCEPROP 1 LASTPIN (5100 3250) $PN 2
J 0
(5062 3262);
DISPLAY 0.787234 (5062 3262);
PAINT MONO (5062 3262);
FORCEPROP 2 LAST CDS_LIB pure_quanta
J 0
(5000 3250);
DISPLAY INVISIBLE (5000 3250);
FORCEPROP 1 LAST PATH I250
J 0
(4950 3400);
DISPLAY 0.978723 (4950 3400);
PAINT WHITE (4950 3400);
DISPLAY INVISIBLE (4950 3400);
FORCEPROP 1 LAST WATTAGE 1/16W
J 2
(5200 3350);
DISPLAY 0.510638 (5200 3350);
DISPLAY INVISIBLE (5200 3350);
FORCEPROP 1 LAST PACK_TYPE 0402LF
J 0
(4900 3350);
DISPLAY 0.510638 (4900 3350);
DISPLAY INVISIBLE (4900 3350);
FORCEPROP 0 LAST CDS_LOCATION R3227
J 0
(4750 3300);
DISPLAY 1.021277 (4750 3300);
DISPLAY INVISIBLE (4750 3300);
FORCEPROP 0 LAST $SEC 1
J 0
(4750 3300);
DISPLAY 0.680851 (4750 3300);
PAINT MONO (4750 3300);
DISPLAY INVISIBLE (4750 3300);
FORCEPROP 0 LAST CDS_SEC 1
J 0
(4750 3300);
DISPLAY 1.021277 (4750 3300);
DISPLAY INVISIBLE (4750 3300);
FORCEADD Q_RES..1
(5000 3300);
FORCEPROP 1 LAST PART_NUMBER CS22202JB07
J 0
(4850 3375);
DISPLAY 0.510638 (4850 3375);
DISPLAY INVISIBLE (4850 3375);
FORCEPROP 1 LAST VALUE 2.2K
J 2
(5225 3300);
DISPLAY 0.510638 (5225 3300);
FORCEPROP 1 LAST WATTAGE 1/16W
J 2
(5150 3425);
DISPLAY 0.510638 (5150 3425);
FORCEPROP 1 LAST TOLERANCE 5%
J 0
(5225 3300);
DISPLAY 0.510638 (5225 3300);
FORCEPROP 1 LAST MATERIAL EMPTY
J 0
(5300 3300);
DISPLAY 0.510638 (5300 3300);
PAINT RED (5300 3300);
FORCEPROP 1 LAST PACK_TYPE 0402LF
J 0
(4850 3425);
DISPLAY 0.510638 (4850 3425);
FORCEPROP 1 LAST $LOCATION R3226
J 0
(4750 3300);
DISPLAY 0.787234 (4750 3300);
FORCEPROP 1 LASTPIN (4900 3300) $PN 1
J 0
(4912 3312);
DISPLAY 0.787234 (4912 3312);
PAINT MONO (4912 3312);
FORCEPROP 1 LASTPIN (5100 3300) $PN 2
J 0
(5062 3312);
DISPLAY 0.787234 (5062 3312);
PAINT MONO (5062 3312);
FORCEPROP 2 LAST CDS_LIB pure_quanta
J 0
(5000 3300);
DISPLAY INVISIBLE (5000 3300);
FORCEPROP 1 LAST PATH I251
J 0
(4950 3450);
DISPLAY 0.978723 (4950 3450);
PAINT WHITE (4950 3450);
DISPLAY INVISIBLE (4950 3450);
FORCEPROP 0 LAST CDS_LOCATION R3226
J 0
(5150 3450);
DISPLAY 1.021277 (5150 3450);
DISPLAY INVISIBLE (5150 3450);
FORCEPROP 0 LAST $SEC 1
J 0
(5150 3450);
DISPLAY 0.680851 (5150 3450);
PAINT MONO (5150 3450);
DISPLAY INVISIBLE (5150 3450);
FORCEPROP 0 LAST CDS_SEC 1
J 0
(5150 3450);
DISPLAY 1.021277 (5150 3450);
DISPLAY INVISIBLE (5150 3450);
FORCEADD OFFPAGE..5
(3500 3300);
FORCEPROP 2 LAST $XR1 240 
J 0
(3095 3300);
DISPLAY 0.638298 (3095 3300);
PAINT MONO (3095 3300);
FORCEPROP 2 LAST $XR0 234 
J 0
(3215 3300);
DISPLAY 0.638298 (3215 3300);
PAINT MONO (3215 3300);
FORCEPROP 2 LAST PATH I252
J 0
(3225 3350);
DISPLAY 1.021277 (3225 3350);
DISPLAY INVISIBLE (3225 3350);
FORCEPROP 1 LAST COMMENT_BODY TRUE
J 0
(3600 3225);
DISPLAY 0.872340 (3600 3225);
PAINT PEACH (3600 3225);
DISPLAY INVISIBLE (3600 3225);
FORCEPROP 1 LAST OFFPAGE TRUE
J 0
(3825 3175);
DISPLAY 0.872340 (3825 3175);
PAINT GREEN (3825 3175);
DISPLAY INVISIBLE (3825 3175);
FORCEPROP 2 LAST CDS_LIB standard
J 0
(3500 3300);
DISPLAY INVISIBLE (3500 3300);
FORCEADD OFFPAGE..5
(3500 3250);
FORCEPROP 2 LAST $XR1 234 
J 0
(3095 3250);
DISPLAY 0.638298 (3095 3250);
PAINT MONO (3095 3250);
FORCEPROP 2 LAST $XR0 240 
J 0
(3215 3250);
DISPLAY 0.638298 (3215 3250);
PAINT MONO (3215 3250);
FORCEPROP 2 LAST PATH I253
J 0
(3225 3300);
DISPLAY 1.021277 (3225 3300);
DISPLAY INVISIBLE (3225 3300);
FORCEPROP 1 LAST COMMENT_BODY TRUE
J 0
(3600 3175);
DISPLAY 0.872340 (3600 3175);
PAINT PEACH (3600 3175);
DISPLAY INVISIBLE (3600 3175);
FORCEPROP 1 LAST OFFPAGE TRUE
J 0
(3825 3125);
DISPLAY 0.872340 (3825 3125);
PAINT GREEN (3825 3125);
DISPLAY INVISIBLE (3825 3125);
FORCEPROP 2 LAST CDS_LIB standard
J 0
(3500 3250);
DISPLAY INVISIBLE (3500 3250);
FORCEADD OFFPAGE..6
(3500 3025);
FORCEPROP 2 LAST $XR1 238 
J 0
(3100 3025);
DISPLAY 0.638298 (3100 3025);
PAINT MONO (3100 3025);
FORCEPROP 2 LAST $XR0 240 
J 0
(3220 3025);
DISPLAY 0.638298 (3220 3025);
PAINT MONO (3220 3025);
FORCEPROP 2 LAST PATH I254
J 0
(3225 3075);
DISPLAY 1.021277 (3225 3075);
DISPLAY INVISIBLE (3225 3075);
FORCEPROP 2 LAST CDS_LIB standard
J 0
(3500 3025);
DISPLAY INVISIBLE (3500 3025);
FORCEPROP 1 LAST COMMENT_BODY TRUE
J 0
(3600 2950);
DISPLAY 0.872340 (3600 2950);
PAINT PEACH (3600 2950);
DISPLAY INVISIBLE (3600 2950);
FORCEPROP 1 LAST OFFPAGE TRUE
J 0
(3825 2900);
DISPLAY 0.872340 (3825 2900);
PAINT GREEN (3825 2900);
DISPLAY INVISIBLE (3825 2900);
FORCEADD OFFPAGE..6
(3500 2975);
FORCEPROP 2 LAST $XR1 240 
J 0
(3100 2975);
DISPLAY 0.638298 (3100 2975);
PAINT MONO (3100 2975);
FORCEPROP 2 LAST $XR0 238 
J 0
(3220 2975);
DISPLAY 0.638298 (3220 2975);
PAINT MONO (3220 2975);
FORCEPROP 2 LAST PATH I255
J 0
(3225 3025);
DISPLAY 1.021277 (3225 3025);
DISPLAY INVISIBLE (3225 3025);
FORCEPROP 1 LAST OFFPAGE TRUE
J 0
(3825 2850);
DISPLAY 0.872340 (3825 2850);
PAINT GREEN (3825 2850);
DISPLAY INVISIBLE (3825 2850);
FORCEPROP 1 LAST COMMENT_BODY TRUE
J 0
(3600 2900);
DISPLAY 0.872340 (3600 2900);
PAINT PEACH (3600 2900);
DISPLAY INVISIBLE (3600 2900);
FORCEPROP 2 LAST CDS_LIB standard
J 0
(3500 2975);
DISPLAY INVISIBLE (3500 2975);
FORCEADD OFFPAGE..6
(3500 2675);
FORCEPROP 2 LAST $XR1 240 
J 0
(3100 2675);
DISPLAY 0.638298 (3100 2675);
PAINT MONO (3100 2675);
FORCEPROP 2 LAST $XR0 238 
J 0
(3220 2675);
DISPLAY 0.638298 (3220 2675);
PAINT MONO (3220 2675);
FORCEPROP 2 LAST PATH I256
J 0
(3225 2725);
DISPLAY 1.021277 (3225 2725);
DISPLAY INVISIBLE (3225 2725);
FORCEPROP 1 LAST COMMENT_BODY TRUE
J 0
(3600 2600);
DISPLAY 0.872340 (3600 2600);
PAINT PEACH (3600 2600);
DISPLAY INVISIBLE (3600 2600);
FORCEPROP 1 LAST OFFPAGE TRUE
J 0
(3825 2550);
DISPLAY 0.872340 (3825 2550);
PAINT GREEN (3825 2550);
DISPLAY INVISIBLE (3825 2550);
FORCEPROP 2 LAST CDS_LIB standard
J 0
(3500 2675);
DISPLAY INVISIBLE (3500 2675);
FORCEADD OFFPAGE..6
(3500 2725);
FORCEPROP 2 LAST $XR1 238 
J 0
(3100 2725);
DISPLAY 0.638298 (3100 2725);
PAINT MONO (3100 2725);
FORCEPROP 2 LAST $XR0 240 
J 0
(3220 2725);
DISPLAY 0.638298 (3220 2725);
PAINT MONO (3220 2725);
FORCEPROP 2 LAST PATH I257
J 0
(3225 2775);
DISPLAY 1.021277 (3225 2775);
DISPLAY INVISIBLE (3225 2775);
FORCEPROP 1 LAST COMMENT_BODY TRUE
J 0
(3600 2650);
DISPLAY 0.872340 (3600 2650);
PAINT PEACH (3600 2650);
DISPLAY INVISIBLE (3600 2650);
FORCEPROP 1 LAST OFFPAGE TRUE
J 0
(3825 2600);
DISPLAY 0.872340 (3825 2600);
PAINT GREEN (3825 2600);
DISPLAY INVISIBLE (3825 2600);
FORCEPROP 2 LAST CDS_LIB standard
J 0
(3500 2725);
DISPLAY INVISIBLE (3500 2725);
FORCEADD Q_RES..1
(5000 2975);
FORCEPROP 1 LAST PART_NUMBER CS22202JB07
J 0
(4900 3025);
DISPLAY 0.510638 (4900 3025);
DISPLAY INVISIBLE (4900 3025);
FORCEPROP 1 LAST TOLERANCE 5%
J 0
(5225 2975);
DISPLAY 0.510638 (5225 2975);
FORCEPROP 1 LAST MATERIAL EMPTY
J 0
(5300 2975);
DISPLAY 0.510638 (5300 2975);
PAINT RED (5300 2975);
FORCEPROP 1 LAST VALUE 2.2K
J 2
(5225 2975);
DISPLAY 0.510638 (5225 2975);
FORCEPROP 1 LAST $LOCATION R3241
J 0
(4750 2975);
DISPLAY 0.808511 (4750 2975);
FORCEPROP 1 LASTPIN (4900 2975) $PN 1
J 0
(4912 2987);
DISPLAY 0.787234 (4912 2987);
PAINT MONO (4912 2987);
FORCEPROP 1 LASTPIN (5100 2975) $PN 2
J 0
(5062 2987);
DISPLAY 0.787234 (5062 2987);
PAINT MONO (5062 2987);
FORCEPROP 1 LAST PACK_TYPE 0402LF
J 0
(4900 3075);
DISPLAY 0.510638 (4900 3075);
DISPLAY INVISIBLE (4900 3075);
FORCEPROP 1 LAST WATTAGE 1/16W
J 2
(5200 3075);
DISPLAY 0.510638 (5200 3075);
DISPLAY INVISIBLE (5200 3075);
FORCEPROP 1 LAST PATH I258
J 0
(4950 3125);
DISPLAY 0.978723 (4950 3125);
PAINT WHITE (4950 3125);
DISPLAY INVISIBLE (4950 3125);
FORCEPROP 2 LAST CDS_LIB pure_quanta
J 0
(5000 2975);
DISPLAY INVISIBLE (5000 2975);
FORCEPROP 0 LAST CDS_LOCATION R3241
J 0
(4950 3075);
DISPLAY 1.021277 (4950 3075);
DISPLAY INVISIBLE (4950 3075);
FORCEPROP 0 LAST $SEC 1
J 0
(4950 3075);
DISPLAY 0.680851 (4950 3075);
PAINT MONO (4950 3075);
DISPLAY INVISIBLE (4950 3075);
FORCEPROP 0 LAST CDS_SEC 1
J 0
(4950 3075);
DISPLAY 1.021277 (4950 3075);
DISPLAY INVISIBLE (4950 3075);
FORCEADD Q_RES..1
(5000 3025);
FORCEPROP 1 LAST PART_NUMBER CS22202JB07
J 0
(4850 3100);
DISPLAY 0.510638 (4850 3100);
DISPLAY INVISIBLE (4850 3100);
FORCEPROP 1 LAST PACK_TYPE 0402LF
J 0
(4850 3150);
DISPLAY 0.510638 (4850 3150);
FORCEPROP 1 LAST MATERIAL EMPTY
J 0
(5300 3025);
DISPLAY 0.510638 (5300 3025);
PAINT RED (5300 3025);
FORCEPROP 1 LAST TOLERANCE 5%
J 0
(5225 3025);
DISPLAY 0.510638 (5225 3025);
FORCEPROP 1 LAST VALUE 2.2K
J 2
(5225 3025);
DISPLAY 0.510638 (5225 3025);
FORCEPROP 1 LAST WATTAGE 1/16W
J 2
(5150 3150);
DISPLAY 0.510638 (5150 3150);
FORCEPROP 1 LAST $LOCATION R3240
J 0
(4750 3025);
DISPLAY 0.808511 (4750 3025);
FORCEPROP 1 LASTPIN (4900 3025) $PN 1
J 0
(4912 3037);
DISPLAY 0.787234 (4912 3037);
PAINT MONO (4912 3037);
FORCEPROP 1 LASTPIN (5100 3025) $PN 2
J 0
(5062 3037);
DISPLAY 0.787234 (5062 3037);
PAINT MONO (5062 3037);
FORCEPROP 1 LAST PATH I259
J 0
(4950 3175);
DISPLAY 0.978723 (4950 3175);
PAINT WHITE (4950 3175);
DISPLAY INVISIBLE (4950 3175);
FORCEPROP 2 LAST CDS_LIB pure_quanta
J 0
(5000 3025);
DISPLAY INVISIBLE (5000 3025);
FORCEPROP 0 LAST CDS_LOCATION R3240
J 0
(5150 3175);
DISPLAY 1.021277 (5150 3175);
DISPLAY INVISIBLE (5150 3175);
FORCEPROP 0 LAST $SEC 1
J 0
(5150 3175);
DISPLAY 0.680851 (5150 3175);
PAINT MONO (5150 3175);
DISPLAY INVISIBLE (5150 3175);
FORCEPROP 0 LAST CDS_SEC 1
J 0
(5150 3175);
DISPLAY 1.021277 (5150 3175);
DISPLAY INVISIBLE (5150 3175);
FORCEADD Q_RES..1
(5000 2725);
FORCEPROP 1 LAST PART_NUMBER CS22202JB07
J 0
(4850 2800);
DISPLAY 0.510638 (4850 2800);
DISPLAY INVISIBLE (4850 2800);
FORCEPROP 1 LAST PACK_TYPE 0402LF
J 0
(4850 2850);
DISPLAY 0.510638 (4850 2850);
FORCEPROP 1 LAST WATTAGE 1/16W
J 2
(5150 2850);
DISPLAY 0.510638 (5150 2850);
FORCEPROP 1 LAST TOLERANCE 5%
J 0
(5225 2725);
DISPLAY 0.510638 (5225 2725);
FORCEPROP 1 LAST VALUE 2.2K
J 2
(5225 2725);
DISPLAY 0.510638 (5225 2725);
FORCEPROP 1 LAST MATERIAL EMPTY
J 0
(5300 2725);
DISPLAY 0.510638 (5300 2725);
PAINT RED (5300 2725);
FORCEPROP 1 LAST $LOCATION R3242
J 0
(4750 2725);
DISPLAY 0.808511 (4750 2725);
FORCEPROP 1 LASTPIN (4900 2725) $PN 1
J 0
(4912 2737);
DISPLAY 0.787234 (4912 2737);
PAINT MONO (4912 2737);
FORCEPROP 1 LASTPIN (5100 2725) $PN 2
J 0
(5062 2737);
DISPLAY 0.787234 (5062 2737);
PAINT MONO (5062 2737);
FORCEPROP 2 LAST CDS_LIB pure_quanta
J 0
(5000 2725);
DISPLAY INVISIBLE (5000 2725);
FORCEPROP 1 LAST PATH I260
J 0
(4950 2875);
DISPLAY 0.978723 (4950 2875);
PAINT WHITE (4950 2875);
DISPLAY INVISIBLE (4950 2875);
FORCEPROP 0 LAST CDS_LOCATION R3242
J 0
(5150 2875);
DISPLAY 1.021277 (5150 2875);
DISPLAY INVISIBLE (5150 2875);
FORCEPROP 0 LAST $SEC 1
J 0
(5150 2875);
DISPLAY 0.680851 (5150 2875);
PAINT MONO (5150 2875);
DISPLAY INVISIBLE (5150 2875);
FORCEPROP 0 LAST CDS_SEC 1
J 0
(5150 2875);
DISPLAY 1.021277 (5150 2875);
DISPLAY INVISIBLE (5150 2875);
FORCEADD Q_RES..1
(5000 2675);
FORCEPROP 1 LAST PART_NUMBER CS22202JB07
J 0
(4900 2725);
DISPLAY 0.510638 (4900 2725);
DISPLAY INVISIBLE (4900 2725);
FORCEPROP 1 LAST MATERIAL EMPTY
J 0
(5300 2675);
DISPLAY 0.510638 (5300 2675);
PAINT RED (5300 2675);
FORCEPROP 1 LAST TOLERANCE 5%
J 0
(5225 2675);
DISPLAY 0.510638 (5225 2675);
FORCEPROP 1 LAST VALUE 2.2K
J 2
(5225 2675);
DISPLAY 0.510638 (5225 2675);
FORCEPROP 1 LAST $LOCATION R3243
J 0
(4750 2675);
DISPLAY 0.808511 (4750 2675);
FORCEPROP 1 LASTPIN (4900 2675) $PN 1
J 0
(4912 2687);
DISPLAY 0.787234 (4912 2687);
PAINT MONO (4912 2687);
FORCEPROP 1 LASTPIN (5100 2675) $PN 2
J 0
(5062 2687);
DISPLAY 0.787234 (5062 2687);
PAINT MONO (5062 2687);
FORCEPROP 2 LAST CDS_LIB pure_quanta
J 0
(5000 2675);
DISPLAY INVISIBLE (5000 2675);
FORCEPROP 1 LAST PATH I261
J 0
(4950 2825);
DISPLAY 0.978723 (4950 2825);
PAINT WHITE (4950 2825);
DISPLAY INVISIBLE (4950 2825);
FORCEPROP 1 LAST PACK_TYPE 0402LF
J 0
(4900 2775);
DISPLAY 0.510638 (4900 2775);
DISPLAY INVISIBLE (4900 2775);
FORCEPROP 1 LAST WATTAGE 1/16W
J 2
(5200 2775);
DISPLAY 0.510638 (5200 2775);
DISPLAY INVISIBLE (5200 2775);
FORCEPROP 0 LAST CDS_LOCATION R3243
J 0
(4950 2775);
DISPLAY 1.021277 (4950 2775);
DISPLAY INVISIBLE (4950 2775);
FORCEPROP 0 LAST $SEC 1
J 0
(4950 2775);
DISPLAY 0.680851 (4950 2775);
PAINT MONO (4950 2775);
DISPLAY INVISIBLE (4950 2775);
FORCEPROP 0 LAST CDS_SEC 1
J 0
(4950 2775);
DISPLAY 1.021277 (4950 2775);
DISPLAY INVISIBLE (4950 2775);
FORCEADD OFFPAGE..3
R 2
(-2025 4800);
FORCEPROP 2 LAST $XR1 241 
J 0
(-2425 4800);
DISPLAY 0.638298 (-2425 4800);
PAINT MONO (-2425 4800);
FORCEPROP 2 LAST $XR0 208 
J 0
(-2305 4800);
DISPLAY 0.638298 (-2305 4800);
PAINT MONO (-2305 4800);
FORCEPROP 1 LAST COMMENT_BODY TRUE
J 2
(-1975 4700);
DISPLAY 0.872340 (-1975 4700);
PAINT GREEN (-1975 4700);
DISPLAY INVISIBLE (-1975 4700);
FORCEPROP 1 LAST OFFPAGE TRUE
J 2
(-2350 4675);
DISPLAY 0.872340 (-2350 4675);
DISPLAY INVISIBLE (-2350 4675);
FORCEPROP 2 LAST PATH I262
J 0
(-1975 4875);
DISPLAY 1.021277 (-1975 4875);
DISPLAY INVISIBLE (-1975 4875);
FORCEPROP 2 LAST CDS_LIB standard
J 0
(-2025 4800);
DISPLAY INVISIBLE (-2025 4800);
FORCEADD OFFPAGE..1
(-2025 4850);
FORCEPROP 2 LAST $XR1 208 
J 0
(-2397 4850);
DISPLAY 0.638298 (-2397 4850);
PAINT MONO (-2397 4850);
FORCEPROP 2 LAST $XR0 241 
J 0
(-2277 4850);
DISPLAY 0.638298 (-2277 4850);
PAINT MONO (-2277 4850);
FORCEPROP 1 LAST OFFPAGE TRUE
J 0
(-1700 4725);
DISPLAY 0.872340 (-1700 4725);
PAINT GREEN (-1700 4725);
DISPLAY INVISIBLE (-1700 4725);
FORCEPROP 1 LAST COMMENT_BODY TRUE
J 0
(-1900 4750);
DISPLAY 0.872340 (-1900 4750);
PAINT GREEN (-1900 4750);
DISPLAY INVISIBLE (-1900 4750);
FORCEPROP 2 LAST PATH I263
J 0
(-1975 4925);
DISPLAY 1.021277 (-1975 4925);
DISPLAY INVISIBLE (-1975 4925);
FORCEPROP 2 LAST CDS_LIB standard
J 0
(-2025 4850);
DISPLAY INVISIBLE (-2025 4850);
FORCEADD Q_RES..1
(-325 4800);
FORCEPROP 1 LAST PART_NUMBER CS03322FB03
J 0
(-450 4900);
DISPLAY 0.510638 (-450 4900);
DISPLAY INVISIBLE (-450 4900);
FORCEPROP 1 LAST MATERIAL CHIP
J 0
(-25 4850);
DISPLAY 0.510638 (-25 4850);
FORCEPROP 1 LAST TOLERANCE 1%
J 0
(-100 4800);
DISPLAY 0.510638 (-100 4800);
FORCEPROP 1 LAST PACK_TYPE 0402LF
J 0
(-450 4925);
DISPLAY 0.510638 (-450 4925);
FORCEPROP 1 LAST WATTAGE 1/16W
J 2
(-150 4925);
DISPLAY 0.510638 (-150 4925);
FORCEPROP 1 LAST VALUE 33.2
J 2
(-125 4800);
DISPLAY 0.510638 (-125 4800);
FORCEPROP 1 LAST $LOCATION R3341
J 0
(-600 4800);
DISPLAY 0.638298 (-600 4800);
FORCEPROP 1 LASTPIN (-425 4800) $PN 1
J 0
(-413 4812);
DISPLAY 0.787234 (-413 4812);
PAINT MONO (-413 4812);
FORCEPROP 1 LASTPIN (-225 4800) $PN 2
J 0
(-263 4812);
DISPLAY 0.787234 (-263 4812);
PAINT MONO (-263 4812);
FORCEPROP 2 LAST CDS_LIB pure_quanta
J 0
(-325 4800);
DISPLAY INVISIBLE (-325 4800);
FORCEPROP 1 LAST PATH I264
J 0
(-375 4950);
DISPLAY 0.978723 (-375 4950);
PAINT WHITE (-375 4950);
DISPLAY INVISIBLE (-375 4950);
FORCEPROP 0 LAST CDS_LOCATION R3341
J 0
(-150 4950);
DISPLAY 1.021277 (-150 4950);
DISPLAY INVISIBLE (-150 4950);
FORCEPROP 0 LAST $SEC 1
J 0
(-150 4950);
DISPLAY 0.680851 (-150 4950);
PAINT MONO (-150 4950);
DISPLAY INVISIBLE (-150 4950);
FORCEPROP 0 LAST CDS_SEC 1
J 0
(-150 4950);
DISPLAY 1.021277 (-150 4950);
DISPLAY INVISIBLE (-150 4950);
FORCEADD OFFPAGE..3
(1350 4800);
FORCEPROP 2 LAST $XR0 212 
J 0
(1564 4800);
DISPLAY 0.638298 (1564 4800);
PAINT MONO (1564 4800);
FORCEPROP 2 LAST PATH I266
J 0
(1575 4850);
DISPLAY 1.021277 (1575 4850);
DISPLAY INVISIBLE (1575 4850);
FORCEPROP 2 LAST CDS_LIB standard
J 0
(1350 4800);
PAINT MONO (1350 4800);
DISPLAY INVISIBLE (1350 4800);
FORCEPROP 1 LAST OFFPAGE TRUE
J 0
(1675 4675);
DISPLAY 0.872340 (1675 4675);
PAINT GREEN (1675 4675);
DISPLAY INVISIBLE (1675 4675);
FORCEPROP 1 LAST COMMENT_BODY TRUE
J 0
(1300 4700);
DISPLAY 0.872340 (1300 4700);
PAINT GREEN (1300 4700);
DISPLAY INVISIBLE (1300 4700);
FORCEADD OFFPAGE..2
(1350 4850);
FORCEPROP 2 LAST $XR0 212 
J 0
(1539 4850);
DISPLAY 0.638298 (1539 4850);
PAINT MONO (1539 4850);
FORCEPROP 2 LAST PATH I267
J 0
(1550 4900);
DISPLAY 1.021277 (1550 4900);
DISPLAY INVISIBLE (1550 4900);
FORCEPROP 2 LAST CDS_LIB standard
J 0
(1350 4850);
PAINT MONO (1350 4850);
DISPLAY INVISIBLE (1350 4850);
FORCEPROP 1 LAST COMMENT_BODY TRUE
J 0
(1305 4755);
DISPLAY 0.872340 (1305 4755);
PAINT GREEN (1305 4755);
DISPLAY INVISIBLE (1305 4755);
FORCEPROP 1 LAST OFFPAGE TRUE
J 0
(1675 4725);
DISPLAY 0.872340 (1675 4725);
PAINT GREEN (1675 4725);
DISPLAY INVISIBLE (1675 4725);
FORCEADD Q_RES..1
(-325 4850);
FORCEPROP 1 LAST PART_NUMBER CS03322FB03
J 0
(-450 5000);
DISPLAY 0.510638 (-450 5000);
DISPLAY INVISIBLE (-450 5000);
FORCEPROP 1 LAST TOLERANCE 1%
J 0
(-100 4850);
DISPLAY 0.510638 (-100 4850);
FORCEPROP 1 LAST MATERIAL CHIP
J 0
(-25 4850);
DISPLAY 0.510638 (-25 4850);
FORCEPROP 1 LAST PACK_TYPE 0402LF
J 0
(-450 5025);
DISPLAY 0.510638 (-450 5025);
FORCEPROP 1 LAST WATTAGE 1/16W
J 2
(-150 5025);
DISPLAY 0.510638 (-150 5025);
FORCEPROP 1 LAST VALUE 33.2
J 2
(-125 4850);
DISPLAY 0.510638 (-125 4850);
FORCEPROP 1 LAST $LOCATION R3340
J 0
(-600 4850);
DISPLAY 0.638298 (-600 4850);
FORCEPROP 1 LASTPIN (-425 4850) $PN 1
J 0
(-413 4862);
DISPLAY 0.787234 (-413 4862);
PAINT MONO (-413 4862);
FORCEPROP 1 LASTPIN (-225 4850) $PN 2
J 0
(-263 4862);
DISPLAY 0.787234 (-263 4862);
PAINT MONO (-263 4862);
FORCEPROP 1 LAST PATH I268
J 0
(-375 5000);
DISPLAY 0.978723 (-375 5000);
PAINT WHITE (-375 5000);
DISPLAY INVISIBLE (-375 5000);
FORCEPROP 2 LAST CDS_LIB pure_quanta
J 0
(-325 4850);
DISPLAY INVISIBLE (-325 4850);
FORCEPROP 0 LAST CDS_LOCATION R3340
J 0
(-150 5050);
DISPLAY 1.021277 (-150 5050);
DISPLAY INVISIBLE (-150 5050);
FORCEPROP 0 LAST $SEC 1
J 0
(-150 5050);
DISPLAY 0.680851 (-150 5050);
PAINT MONO (-150 5050);
DISPLAY INVISIBLE (-150 5050);
FORCEPROP 0 LAST CDS_SEC 1
J 0
(-150 5050);
DISPLAY 1.021277 (-150 5050);
DISPLAY INVISIBLE (-150 5050);
FORCEADD OFFPAGE..3
R 2
(-2100 975);
FORCEPROP 2 LAST $XR0 240 
J 0
(-2410 975);
DISPLAY 0.638298 (-2410 975);
PAINT MONO (-2410 975);
FORCEPROP 2 LAST CDS_LIB standard
J 0
(-2100 975);
DISPLAY INVISIBLE (-2100 975);
FORCEPROP 2 LAST PATH I269
J 0
(-2050 1050);
DISPLAY 1.021277 (-2050 1050);
DISPLAY INVISIBLE (-2050 1050);
FORCEPROP 1 LAST COMMENT_BODY TRUE
J 2
(-2050 875);
DISPLAY 0.872340 (-2050 875);
PAINT GREEN (-2050 875);
DISPLAY INVISIBLE (-2050 875);
FORCEPROP 1 LAST OFFPAGE TRUE
J 2
(-2425 850);
DISPLAY 0.872340 (-2425 850);
DISPLAY INVISIBLE (-2425 850);
FORCEADD OFFPAGE..1
(-2100 1025);
FORCEPROP 2 LAST $XR0 240 
J 0
(-2382 1025);
DISPLAY 0.638298 (-2382 1025);
PAINT MONO (-2382 1025);
FORCEPROP 2 LAST CDS_LIB standard
J 0
(-2100 1025);
DISPLAY INVISIBLE (-2100 1025);
FORCEPROP 2 LAST PATH I270
J 0
(-2050 1100);
DISPLAY 1.021277 (-2050 1100);
DISPLAY INVISIBLE (-2050 1100);
FORCEPROP 1 LAST OFFPAGE TRUE
J 0
(-1775 900);
DISPLAY 0.872340 (-1775 900);
PAINT GREEN (-1775 900);
DISPLAY INVISIBLE (-1775 900);
FORCEPROP 1 LAST COMMENT_BODY TRUE
J 0
(-1975 925);
DISPLAY 0.872340 (-1975 925);
PAINT GREEN (-1975 925);
DISPLAY INVISIBLE (-1975 925);
FORCEADD Q_RES..1
(-350 975);
FORCEPROP 1 LAST PART_NUMBER CS03322FB03
J 0
(-475 1025);
DISPLAY 0.638298 (-475 1025);
DISPLAY INVISIBLE (-475 1025);
FORCEPROP 1 LAST TOLERANCE 1%
J 0
(-125 975);
DISPLAY 0.510638 (-125 975);
FORCEPROP 1 LAST VALUE 33.2
J 2
(-150 975);
DISPLAY 0.510638 (-150 975);
FORCEPROP 1 LAST MATERIAL CHIP
J 0
(-50 975);
DISPLAY 0.510638 (-50 975);
FORCEPROP 1 LAST $LOCATION R4150
J 0
(-525 975);
DISPLAY 0.638298 (-525 975);
FORCEPROP 1 LASTPIN (-450 975) $PN 1
J 0
(-438 987);
DISPLAY 0.787234 (-438 987);
PAINT MONO (-438 987);
FORCEPROP 1 LASTPIN (-250 975) $PN 2
J 0
(-288 987);
DISPLAY 0.787234 (-288 987);
PAINT MONO (-288 987);
FORCEPROP 1 LAST PACK_TYPE 0402LF
J 0
(0 975);
DISPLAY 0.638298 (0 975);
DISPLAY INVISIBLE (0 975);
FORCEPROP 1 LAST WATTAGE 1/16W
J 2
(-150 1075);
DISPLAY 0.638298 (-150 1075);
DISPLAY INVISIBLE (-150 1075);
FORCEPROP 1 LAST PATH I271
J 0
(-400 1125);
DISPLAY 0.978723 (-400 1125);
PAINT WHITE (-400 1125);
DISPLAY INVISIBLE (-400 1125);
FORCEPROP 2 LAST CDS_LIB pure_quanta
J 0
(-350 975);
DISPLAY INVISIBLE (-350 975);
FORCEPROP 0 LAST CDS_LOCATION R4150
J 0
(-525 1025);
DISPLAY 1.021277 (-525 1025);
DISPLAY INVISIBLE (-525 1025);
FORCEPROP 0 LAST $SEC 1
J 0
(-525 1025);
DISPLAY 0.680851 (-525 1025);
PAINT MONO (-525 1025);
DISPLAY INVISIBLE (-525 1025);
FORCEPROP 0 LAST CDS_SEC 1
J 0
(-525 1025);
DISPLAY 1.021277 (-525 1025);
DISPLAY INVISIBLE (-525 1025);
FORCEADD Q_RES..1
(-350 1025);
FORCEPROP 1 LAST PART_NUMBER CS03322FB03
J 0
(-475 1100);
DISPLAY 0.510638 (-475 1100);
DISPLAY INVISIBLE (-475 1100);
FORCEPROP 1 LAST VALUE 33.2
J 2
(-150 1025);
DISPLAY 0.510638 (-150 1025);
FORCEPROP 1 LAST TOLERANCE 1%
J 0
(-125 1025);
DISPLAY 0.510638 (-125 1025);
FORCEPROP 1 LAST MATERIAL CHIP
J 0
(-50 1025);
DISPLAY 0.510638 (-50 1025);
FORCEPROP 1 LAST PACK_TYPE 0402LF
J 0
(-475 1150);
DISPLAY 0.510638 (-475 1150);
FORCEPROP 1 LAST WATTAGE 1/16W
J 2
(-175 1150);
DISPLAY 0.510638 (-175 1150);
FORCEPROP 1 LAST $LOCATION R4149
J 0
(-525 1025);
DISPLAY 0.638298 (-525 1025);
FORCEPROP 1 LASTPIN (-450 1025) $PN 1
J 0
(-438 1037);
DISPLAY 0.787234 (-438 1037);
PAINT MONO (-438 1037);
FORCEPROP 1 LASTPIN (-250 1025) $PN 2
J 0
(-288 1037);
DISPLAY 0.787234 (-288 1037);
PAINT MONO (-288 1037);
FORCEPROP 1 LAST PATH I272
J 0
(-400 1175);
DISPLAY 0.978723 (-400 1175);
PAINT WHITE (-400 1175);
DISPLAY INVISIBLE (-400 1175);
FORCEPROP 2 LAST CDS_LIB pure_quanta
J 0
(-350 1025);
DISPLAY INVISIBLE (-350 1025);
FORCEPROP 0 LAST CDS_LOCATION R4149
J 0
(-175 1175);
DISPLAY 1.021277 (-175 1175);
DISPLAY INVISIBLE (-175 1175);
FORCEPROP 0 LAST $SEC 1
J 0
(-175 1175);
DISPLAY 0.680851 (-175 1175);
PAINT MONO (-175 1175);
DISPLAY INVISIBLE (-175 1175);
FORCEPROP 0 LAST CDS_SEC 1
J 0
(-175 1175);
DISPLAY 1.021277 (-175 1175);
DISPLAY INVISIBLE (-175 1175);
FORCEADD Q_RES..1
(-350 700);
FORCEPROP 1 LAST PART_NUMBER CS03322FB03
J 0
(-475 750);
DISPLAY 0.638298 (-475 750);
DISPLAY INVISIBLE (-475 750);
FORCEPROP 1 LAST TOLERANCE 1%
J 0
(-125 700);
DISPLAY 0.510638 (-125 700);
FORCEPROP 1 LAST VALUE 33.2
J 2
(-150 700);
DISPLAY 0.510638 (-150 700);
FORCEPROP 1 LAST MATERIAL CHIP
J 0
(-50 700);
DISPLAY 0.510638 (-50 700);
FORCEPROP 1 LAST $LOCATION R4152
J 0
(-525 700);
DISPLAY 0.638298 (-525 700);
FORCEPROP 1 LASTPIN (-450 700) $PN 1
J 0
(-438 712);
DISPLAY 0.787234 (-438 712);
PAINT MONO (-438 712);
FORCEPROP 1 LASTPIN (-250 700) $PN 2
J 0
(-288 712);
DISPLAY 0.787234 (-288 712);
PAINT MONO (-288 712);
FORCEPROP 2 LAST CDS_LIB pure_quanta
J 0
(-350 700);
DISPLAY INVISIBLE (-350 700);
FORCEPROP 1 LAST PATH I273
J 0
(-400 850);
DISPLAY 0.978723 (-400 850);
PAINT WHITE (-400 850);
DISPLAY INVISIBLE (-400 850);
FORCEPROP 1 LAST PACK_TYPE 0402LF
J 0
(0 700);
DISPLAY 0.638298 (0 700);
DISPLAY INVISIBLE (0 700);
FORCEPROP 1 LAST WATTAGE 1/16W
J 2
(-150 800);
DISPLAY 0.638298 (-150 800);
DISPLAY INVISIBLE (-150 800);
FORCEPROP 0 LAST CDS_LOCATION R4152
J 0
(-525 750);
DISPLAY 1.021277 (-525 750);
DISPLAY INVISIBLE (-525 750);
FORCEPROP 0 LAST $SEC 1
J 0
(-525 750);
DISPLAY 0.680851 (-525 750);
PAINT MONO (-525 750);
DISPLAY INVISIBLE (-525 750);
FORCEPROP 0 LAST CDS_SEC 1
J 0
(-525 750);
DISPLAY 1.021277 (-525 750);
DISPLAY INVISIBLE (-525 750);
FORCEADD Q_RES..1
(-350 750);
FORCEPROP 1 LAST PART_NUMBER CS03322FB03
J 0
(-475 825);
DISPLAY 0.510638 (-475 825);
DISPLAY INVISIBLE (-475 825);
FORCEPROP 1 LAST WATTAGE 1/16W
J 2
(-175 875);
DISPLAY 0.510638 (-175 875);
FORCEPROP 1 LAST PACK_TYPE 0402LF
J 0
(-475 875);
DISPLAY 0.510638 (-475 875);
FORCEPROP 1 LAST VALUE 33.2
J 2
(-150 750);
DISPLAY 0.510638 (-150 750);
FORCEPROP 1 LAST MATERIAL CHIP
J 0
(-50 750);
DISPLAY 0.510638 (-50 750);
FORCEPROP 1 LAST TOLERANCE 1%
J 0
(-125 750);
DISPLAY 0.510638 (-125 750);
FORCEPROP 1 LAST $LOCATION R4151
J 0
(-525 750);
DISPLAY 0.638298 (-525 750);
FORCEPROP 1 LASTPIN (-450 750) $PN 1
J 0
(-438 762);
DISPLAY 0.787234 (-438 762);
PAINT MONO (-438 762);
FORCEPROP 1 LASTPIN (-250 750) $PN 2
J 0
(-288 762);
DISPLAY 0.787234 (-288 762);
PAINT MONO (-288 762);
FORCEPROP 2 LAST CDS_LIB pure_quanta
J 0
(-350 750);
DISPLAY INVISIBLE (-350 750);
FORCEPROP 1 LAST PATH I274
J 0
(-400 900);
DISPLAY 0.978723 (-400 900);
PAINT WHITE (-400 900);
DISPLAY INVISIBLE (-400 900);
FORCEPROP 0 LAST CDS_LOCATION R4151
J 0
(-175 900);
DISPLAY 1.021277 (-175 900);
DISPLAY INVISIBLE (-175 900);
FORCEPROP 0 LAST $SEC 1
J 0
(-175 900);
DISPLAY 0.680851 (-175 900);
PAINT MONO (-175 900);
DISPLAY INVISIBLE (-175 900);
FORCEPROP 0 LAST CDS_SEC 1
J 0
(-175 900);
DISPLAY 1.021277 (-175 900);
DISPLAY INVISIBLE (-175 900);
FORCEADD OFFPAGE..3
(1325 975);
FORCEPROP 2 LAST $XR0 213 
J 0
(1539 975);
DISPLAY 0.638298 (1539 975);
PAINT MONO (1539 975);
FORCEPROP 2 LAST CDS_LIB standard
J 0
(1325 975);
DISPLAY INVISIBLE (1325 975);
FORCEPROP 2 LAST PATH I275
J 0
(1525 1050);
DISPLAY 1.021277 (1525 1050);
DISPLAY INVISIBLE (1525 1050);
FORCEPROP 1 LAST OFFPAGE TRUE
J 0
(1650 850);
DISPLAY 0.872340 (1650 850);
DISPLAY INVISIBLE (1650 850);
FORCEPROP 1 LAST COMMENT_BODY TRUE
J 0
(1275 875);
DISPLAY 0.872340 (1275 875);
PAINT GREEN (1275 875);
DISPLAY INVISIBLE (1275 875);
FORCEADD OFFPAGE..2
(1325 1025);
FORCEPROP 2 LAST $XR0 213 
J 0
(1514 1025);
DISPLAY 0.638298 (1514 1025);
PAINT MONO (1514 1025);
FORCEPROP 2 LAST CDS_LIB standard
J 0
(1325 1025);
DISPLAY INVISIBLE (1325 1025);
FORCEPROP 2 LAST PATH I276
J 0
(1500 1100);
DISPLAY 1.021277 (1500 1100);
DISPLAY INVISIBLE (1500 1100);
FORCEPROP 1 LAST OFFPAGE TRUE
J 0
(1650 900);
DISPLAY 1.170213 (1650 900);
PAINT GREEN (1650 900);
DISPLAY INVISIBLE (1650 900);
FORCEPROP 1 LAST COMMENT_BODY TRUE
J 0
(1280 930);
DISPLAY 1.170213 (1280 930);
PAINT GREEN (1280 930);
DISPLAY INVISIBLE (1280 930);
FORCEADD OFFPAGE..2
(1325 750);
FORCEPROP 2 LAST $XR0 214 
J 0
(1514 750);
DISPLAY 0.638298 (1514 750);
PAINT MONO (1514 750);
FORCEPROP 2 LAST CDS_LIB standard
J 0
(1325 750);
DISPLAY INVISIBLE (1325 750);
FORCEPROP 2 LAST PATH I277
J 0
(1500 825);
DISPLAY 1.021277 (1500 825);
DISPLAY INVISIBLE (1500 825);
FORCEPROP 1 LAST COMMENT_BODY TRUE
J 0
(1280 655);
DISPLAY 1.170213 (1280 655);
PAINT GREEN (1280 655);
DISPLAY INVISIBLE (1280 655);
FORCEPROP 1 LAST OFFPAGE TRUE
J 0
(1650 625);
DISPLAY 1.170213 (1650 625);
PAINT GREEN (1650 625);
DISPLAY INVISIBLE (1650 625);
FORCEADD OFFPAGE..3
(1325 700);
FORCEPROP 2 LAST $XR0 214 
J 0
(1539 700);
DISPLAY 0.638298 (1539 700);
PAINT MONO (1539 700);
FORCEPROP 2 LAST CDS_LIB standard
J 0
(1325 700);
DISPLAY INVISIBLE (1325 700);
FORCEPROP 2 LAST PATH I278
J 0
(1525 775);
DISPLAY 1.021277 (1525 775);
DISPLAY INVISIBLE (1525 775);
FORCEPROP 1 LAST COMMENT_BODY TRUE
J 0
(1275 600);
DISPLAY 0.872340 (1275 600);
PAINT GREEN (1275 600);
DISPLAY INVISIBLE (1275 600);
FORCEPROP 1 LAST OFFPAGE TRUE
J 0
(1650 575);
DISPLAY 0.872340 (1650 575);
DISPLAY INVISIBLE (1650 575);
FORCEADD OFFPAGE..2
(5675 2050);
FORCEPROP 2 LAST $XR0 229 
J 0
(5864 2050);
DISPLAY 0.638298 (5864 2050);
PAINT MONO (5864 2050);
FORCEPROP 2 LAST CDS_LIB standard
J 0
(5675 2050);
PAINT MONO (5675 2050);
DISPLAY INVISIBLE (5675 2050);
FORCEPROP 1 LAST COMMENT_BODY TRUE
J 0
(5630 1955);
DISPLAY 0.872340 (5630 1955);
PAINT GREEN (5630 1955);
DISPLAY INVISIBLE (5630 1955);
FORCEPROP 1 LAST OFFPAGE TRUE
J 0
(6000 1925);
DISPLAY 0.872340 (6000 1925);
PAINT GREEN (6000 1925);
DISPLAY INVISIBLE (6000 1925);
FORCEPROP 2 LAST PATH I28
J 0
(5875 2100);
DISPLAY 1.021277 (5875 2100);
DISPLAY INVISIBLE (5875 2100);
FORCEADD Q_RES..1
(-350 6675);
FORCEPROP 1 LAST PART_NUMBER CS00002JB13
J 0
(-400 6725);
DISPLAY 0.404255 (-400 6725);
DISPLAY INVISIBLE (-400 6725);
FORCEPROP 1 LAST VALUE 0
J 2
(-150 6675);
DISPLAY 0.510638 (-150 6675);
FORCEPROP 1 LAST MATERIAL CHIP
J 0
(-50 6675);
DISPLAY 0.510638 (-50 6675);
FORCEPROP 1 LAST TOLERANCE 5%
J 0
(-125 6675);
DISPLAY 0.510638 (-125 6675);
FORCEPROP 1 LAST $LOCATION R4511
J 0
(-600 6675);
DISPLAY 0.787234 (-600 6675);
FORCEPROP 1 LASTPIN (-450 6675) $PN 1
J 0
(-438 6687);
DISPLAY 0.787234 (-438 6687);
PAINT MONO (-438 6687);
FORCEPROP 1 LASTPIN (-250 6675) $PN 2
J 0
(-288 6687);
DISPLAY 0.787234 (-288 6687);
PAINT MONO (-288 6687);
FORCEPROP 1 LAST WATTAGE 1/16W
J 2
(-175 6750);
DISPLAY 0.404255 (-175 6750);
DISPLAY INVISIBLE (-175 6750);
FORCEPROP 1 LAST PACK_TYPE 0402LF
J 0
(-100 6675);
DISPLAY 0.510638 (-100 6675);
DISPLAY INVISIBLE (-100 6675);
FORCEPROP 1 LAST PATH I284
J 0
(-400 6825);
DISPLAY 0.978723 (-400 6825);
PAINT WHITE (-400 6825);
DISPLAY INVISIBLE (-400 6825);
FORCEPROP 2 LAST CDS_LIB pure_quanta
J 0
(-350 6675);
DISPLAY INVISIBLE (-350 6675);
FORCEPROP 0 LAST CDS_LOCATION R4511
J 0
(-525 6725);
DISPLAY 1.021277 (-525 6725);
DISPLAY INVISIBLE (-525 6725);
FORCEPROP 0 LAST $SEC 1
J 0
(-525 6725);
DISPLAY 0.680851 (-525 6725);
PAINT MONO (-525 6725);
DISPLAY INVISIBLE (-525 6725);
FORCEPROP 0 LAST CDS_SEC 1
J 0
(-525 6725);
DISPLAY 1.021277 (-525 6725);
DISPLAY INVISIBLE (-525 6725);
FORCEADD Q_RES..1
(-350 6725);
FORCEPROP 1 LAST PART_NUMBER CS03322FB03
J 0
(-475 6800);
DISPLAY 0.510638 (-475 6800);
DISPLAY INVISIBLE (-475 6800);
FORCEPROP 1 LAST VALUE 33.2
J 2
(-150 6725);
DISPLAY 0.510638 (-150 6725);
FORCEPROP 1 LAST TOLERANCE 1%
J 0
(-125 6725);
DISPLAY 0.510638 (-125 6725);
FORCEPROP 1 LAST WATTAGE 1/16W
J 2
(-175 6850);
DISPLAY 0.510638 (-175 6850);
FORCEPROP 1 LAST MATERIAL CHIP
J 0
(-50 6725);
DISPLAY 0.510638 (-50 6725);
FORCEPROP 1 LAST PACK_TYPE 0402LF
J 0
(-475 6850);
DISPLAY 0.510638 (-475 6850);
FORCEPROP 1 LAST $LOCATION R4510
J 0
(-600 6725);
DISPLAY 0.787234 (-600 6725);
FORCEPROP 1 LASTPIN (-450 6725) $PN 1
J 0
(-438 6737);
DISPLAY 0.787234 (-438 6737);
PAINT MONO (-438 6737);
FORCEPROP 1 LASTPIN (-250 6725) $PN 2
J 0
(-288 6737);
DISPLAY 0.787234 (-288 6737);
PAINT MONO (-288 6737);
FORCEPROP 2 LAST CDS_LIB pure_quanta
J 0
(-350 6725);
DISPLAY INVISIBLE (-350 6725);
FORCEPROP 1 LAST PATH I285
J 0
(-400 6875);
DISPLAY 0.978723 (-400 6875);
PAINT WHITE (-400 6875);
DISPLAY INVISIBLE (-400 6875);
FORCEPROP 0 LAST CDS_LOCATION R4510
J 0
(-175 6875);
DISPLAY 1.021277 (-175 6875);
DISPLAY INVISIBLE (-175 6875);
FORCEPROP 0 LAST $SEC 1
J 0
(-175 6875);
DISPLAY 0.680851 (-175 6875);
PAINT MONO (-175 6875);
DISPLAY INVISIBLE (-175 6875);
FORCEPROP 0 LAST CDS_SEC 1
J 0
(-175 6875);
DISPLAY 1.021277 (-175 6875);
DISPLAY INVISIBLE (-175 6875);
FORCEADD OFFPAGE..1
(-2275 6725);
FORCEPROP 2 LAST $XR1 241 
J 0
(-2647 6725);
DISPLAY 0.638298 (-2647 6725);
PAINT MONO (-2647 6725);
FORCEPROP 2 LAST $XR0 240 
J 0
(-2527 6725);
DISPLAY 0.638298 (-2527 6725);
PAINT MONO (-2527 6725);
FORCEPROP 2 LAST CDS_LIB standard
J 0
(-2275 6725);
PAINT MONO (-2275 6725);
DISPLAY INVISIBLE (-2275 6725);
FORCEPROP 2 LAST PATH I286
J 0
(-2550 6775);
DISPLAY 1.021277 (-2550 6775);
DISPLAY INVISIBLE (-2550 6775);
FORCEPROP 1 LAST COMMENT_BODY TRUE
J 0
(-2150 6625);
DISPLAY 0.872340 (-2150 6625);
PAINT GREEN (-2150 6625);
DISPLAY INVISIBLE (-2150 6625);
FORCEPROP 1 LAST OFFPAGE TRUE
J 0
(-1950 6600);
DISPLAY 0.872340 (-1950 6600);
PAINT GREEN (-1950 6600);
DISPLAY INVISIBLE (-1950 6600);
FORCEADD OFFPAGE..3
R 2
(-2275 6675);
FORCEPROP 2 LAST $XR1 241 
J 0
(-2675 6675);
DISPLAY 0.638298 (-2675 6675);
PAINT MONO (-2675 6675);
FORCEPROP 2 LAST $XR0 240 
J 0
(-2555 6675);
DISPLAY 0.638298 (-2555 6675);
PAINT MONO (-2555 6675);
FORCEPROP 2 LAST CDS_LIB standard
J 0
(-2275 6675);
PAINT MONO (-2275 6675);
DISPLAY INVISIBLE (-2275 6675);
FORCEPROP 2 LAST PATH I287
J 0
(-2575 6725);
DISPLAY 1.021277 (-2575 6725);
DISPLAY INVISIBLE (-2575 6725);
FORCEPROP 1 LAST OFFPAGE TRUE
J 2
(-2600 6550);
DISPLAY 0.872340 (-2600 6550);
DISPLAY INVISIBLE (-2600 6550);
FORCEPROP 1 LAST COMMENT_BODY TRUE
J 2
(-2225 6575);
DISPLAY 0.872340 (-2225 6575);
PAINT GREEN (-2225 6575);
DISPLAY INVISIBLE (-2225 6575);
FORCEADD OFFPAGE..2
(1400 6725);
FORCEPROP 2 LAST $XR2 241 
J 0
(1829 6725);
DISPLAY 0.638298 (1829 6725);
PAINT MONO (1829 6725);
FORCEPROP 2 LAST $XR1 213 
J 0
(1709 6725);
DISPLAY 0.638298 (1709 6725);
PAINT MONO (1709 6725);
FORCEPROP 2 LAST $XR0 131 
J 0
(1589 6725);
DISPLAY 0.638298 (1589 6725);
PAINT MONO (1589 6725);
FORCEPROP 2 LAST CDS_LIB standard
J 0
(1400 6725);
DISPLAY INVISIBLE (1400 6725);
FORCEPROP 2 LAST PATH I288
J 0
(1575 6800);
DISPLAY 1.021277 (1575 6800);
DISPLAY INVISIBLE (1575 6800);
FORCEPROP 1 LAST COMMENT_BODY TRUE
J 0
(1355 6630);
DISPLAY 0.872340 (1355 6630);
PAINT GREEN (1355 6630);
DISPLAY INVISIBLE (1355 6630);
FORCEPROP 1 LAST OFFPAGE TRUE
J 0
(1725 6600);
DISPLAY 0.872340 (1725 6600);
PAINT GREEN (1725 6600);
DISPLAY INVISIBLE (1725 6600);
FORCEADD OFFPAGE..3
(1400 6675);
FORCEPROP 2 LAST $XR2 241 
J 0
(1854 6675);
DISPLAY 0.638298 (1854 6675);
PAINT MONO (1854 6675);
FORCEPROP 2 LAST $XR1 213 
J 0
(1734 6675);
DISPLAY 0.638298 (1734 6675);
PAINT MONO (1734 6675);
FORCEPROP 2 LAST $XR0 131 
J 0
(1614 6675);
DISPLAY 0.638298 (1614 6675);
PAINT MONO (1614 6675);
FORCEPROP 2 LAST CDS_LIB standard
J 0
(1400 6675);
DISPLAY INVISIBLE (1400 6675);
FORCEPROP 2 LAST PATH I289
J 0
(1600 6750);
DISPLAY 1.021277 (1600 6750);
DISPLAY INVISIBLE (1600 6750);
FORCEPROP 1 LAST OFFPAGE TRUE
J 0
(1725 6550);
DISPLAY 0.872340 (1725 6550);
PAINT GREEN (1725 6550);
DISPLAY INVISIBLE (1725 6550);
FORCEPROP 1 LAST COMMENT_BODY TRUE
J 0
(1350 6575);
DISPLAY 0.872340 (1350 6575);
PAINT GREEN (1350 6575);
DISPLAY INVISIBLE (1350 6575);
FORCEADD OFFPAGE..3
(5675 2000);
FORCEPROP 2 LAST $XR0 229 
J 0
(5889 2000);
DISPLAY 0.638298 (5889 2000);
PAINT MONO (5889 2000);
FORCEPROP 2 LAST CDS_LIB standard
J 0
(5675 2000);
PAINT MONO (5675 2000);
DISPLAY INVISIBLE (5675 2000);
FORCEPROP 1 LAST OFFPAGE TRUE
J 0
(6000 1875);
DISPLAY 0.872340 (6000 1875);
PAINT GREEN (6000 1875);
DISPLAY INVISIBLE (6000 1875);
FORCEPROP 1 LAST COMMENT_BODY TRUE
J 0
(5625 1900);
DISPLAY 0.872340 (5625 1900);
PAINT GREEN (5625 1900);
DISPLAY INVISIBLE (5625 1900);
FORCEPROP 2 LAST PATH I29
J 0
(5900 2050);
DISPLAY 1.021277 (5900 2050);
DISPLAY INVISIBLE (5900 2050);
FORCEADD OFFPAGE..2
(1375 3525);
FORCEPROP 2 LAST $XR1 305 
J 0
(1684 3525);
DISPLAY 0.638298 (1684 3525);
PAINT MONO (1684 3525);
FORCEPROP 2 LAST $XR0 301 
J 0
(1564 3525);
DISPLAY 0.638298 (1564 3525);
PAINT MONO (1564 3525);
FORCEPROP 2 LAST PATH I290
J 0
(1700 3575);
DISPLAY 1.021277 (1700 3575);
DISPLAY INVISIBLE (1700 3575);
FORCEPROP 2 LAST CDS_LIB standard
J 0
(1375 3525);
PAINT MONO (1375 3525);
DISPLAY INVISIBLE (1375 3525);
FORCEPROP 1 LAST OFFPAGE TRUE
J 0
(1700 3400);
DISPLAY 1.170213 (1700 3400);
PAINT GREEN (1700 3400);
DISPLAY INVISIBLE (1700 3400);
FORCEPROP 1 LAST COMMENT_BODY TRUE
J 0
(1330 3430);
DISPLAY 1.170213 (1330 3430);
PAINT GREEN (1330 3430);
DISPLAY INVISIBLE (1330 3430);
FORCEADD OFFPAGE..3
(1375 3475);
FORCEPROP 2 LAST $XR1 305 
J 0
(1709 3475);
DISPLAY 0.638298 (1709 3475);
PAINT MONO (1709 3475);
FORCEPROP 2 LAST $XR0 301 
J 0
(1589 3475);
DISPLAY 0.638298 (1589 3475);
PAINT MONO (1589 3475);
FORCEPROP 2 LAST PATH I291
J 0
(1725 3525);
DISPLAY 1.021277 (1725 3525);
DISPLAY INVISIBLE (1725 3525);
FORCEPROP 1 LAST OFFPAGE TRUE
J 0
(1700 3350);
DISPLAY 0.872340 (1700 3350);
DISPLAY INVISIBLE (1700 3350);
FORCEPROP 1 LAST COMMENT_BODY TRUE
J 0
(1325 3375);
DISPLAY 0.872340 (1325 3375);
PAINT GREEN (1325 3375);
DISPLAY INVISIBLE (1325 3375);
FORCEPROP 2 LAST CDS_LIB standard
J 0
(1375 3475);
PAINT MONO (1375 3475);
DISPLAY INVISIBLE (1375 3475);
FORCEADD Q_RES..1
(-300 3525);
FORCEPROP 1 LAST PART_NUMBER CS03322FB03
J 0
(-425 3600);
DISPLAY 0.510638 (-425 3600);
DISPLAY INVISIBLE (-425 3600);
FORCEPROP 1 LAST TOLERANCE 1%
J 0
(-75 3525);
DISPLAY 0.510638 (-75 3525);
FORCEPROP 1 LAST VALUE 33.2
J 2
(-100 3525);
DISPLAY 0.510638 (-100 3525);
FORCEPROP 1 LAST WATTAGE 1/16W
J 2
(-125 3650);
DISPLAY 0.510638 (-125 3650);
FORCEPROP 1 LAST PACK_TYPE 0402LF
J 0
(-425 3650);
DISPLAY 0.510638 (-425 3650);
FORCEPROP 1 LAST MATERIAL CHIP
J 0
(0 3525);
DISPLAY 0.510638 (0 3525);
FORCEPROP 1 LAST LOCATION R4530
J 0
(-550 3525);
DISPLAY 0.808511 (-550 3525);
FORCEPROP 1 LASTPIN (-400 3525) $PN 1
J 0
(-388 3537);
DISPLAY 0.787234 (-388 3537);
FORCEPROP 1 LASTPIN (-200 3525) $PN 2
J 0
(-238 3537);
DISPLAY 0.787234 (-238 3537);
FORCEPROP 1 LAST PATH I293
J 0
(-350 3675);
DISPLAY 0.978723 (-350 3675);
PAINT WHITE (-350 3675);
DISPLAY INVISIBLE (-350 3675);
FORCEPROP 2 LAST CDS_LIB pure_quanta
J 0
(-300 3525);
DISPLAY INVISIBLE (-300 3525);
FORCEPROP 0 LAST $SEC 1
J 0
(-125 3675);
DISPLAY 0.680851 (-125 3675);
PAINT MONO (-125 3675);
DISPLAY INVISIBLE (-125 3675);
FORCEPROP 0 LAST CDS_SEC 1
J 0
(-125 3675);
DISPLAY 1.021277 (-125 3675);
DISPLAY INVISIBLE (-125 3675);
FORCEADD OFFPAGE..1
(-2050 3525);
FORCEPROP 2 LAST $XR0 241 
J 0
(-2302 3525);
DISPLAY 0.638298 (-2302 3525);
PAINT MONO (-2302 3525);
FORCEPROP 2 LAST PATH I294
J 0
(-2300 3575);
DISPLAY 1.021277 (-2300 3575);
DISPLAY INVISIBLE (-2300 3575);
FORCEPROP 1 LAST COMMENT_BODY TRUE
J 0
(-1925 3425);
DISPLAY 0.872340 (-1925 3425);
PAINT GREEN (-1925 3425);
DISPLAY INVISIBLE (-1925 3425);
FORCEPROP 1 LAST OFFPAGE TRUE
J 0
(-1725 3400);
DISPLAY 0.872340 (-1725 3400);
PAINT GREEN (-1725 3400);
DISPLAY INVISIBLE (-1725 3400);
FORCEPROP 2 LAST CDS_LIB standard
J 0
(-2050 3525);
PAINT MONO (-2050 3525);
DISPLAY INVISIBLE (-2050 3525);
FORCEADD OFFPAGE..3
R 2
(-2050 3475);
FORCEPROP 2 LAST $XR0 241 
J 0
(-2330 3475);
DISPLAY 0.638298 (-2330 3475);
PAINT MONO (-2330 3475);
FORCEPROP 2 LAST PATH I295
J 0
(-2325 3525);
DISPLAY 1.021277 (-2325 3525);
DISPLAY INVISIBLE (-2325 3525);
FORCEPROP 1 LAST OFFPAGE TRUE
J 2
(-2375 3350);
DISPLAY 0.872340 (-2375 3350);
DISPLAY INVISIBLE (-2375 3350);
FORCEPROP 1 LAST COMMENT_BODY TRUE
J 2
(-2000 3375);
DISPLAY 0.872340 (-2000 3375);
PAINT GREEN (-2000 3375);
DISPLAY INVISIBLE (-2000 3375);
FORCEPROP 2 LAST CDS_LIB standard
J 0
(-2050 3475);
PAINT MONO (-2050 3475);
DISPLAY INVISIBLE (-2050 3475);
FORCEADD Q_RES..1
(-300 3475);
FORCEPROP 1 LAST PART_NUMBER CS00002JB13
J 0
(-350 3525);
DISPLAY 0.404255 (-350 3525);
DISPLAY INVISIBLE (-350 3525);
FORCEPROP 1 LAST TOLERANCE 5%
J 0
(-75 3475);
DISPLAY 0.510638 (-75 3475);
FORCEPROP 1 LAST MATERIAL CHIP
J 0
(0 3475);
DISPLAY 0.510638 (0 3475);
FORCEPROP 1 LAST VALUE 0
J 2
(-100 3475);
DISPLAY 0.510638 (-100 3475);
FORCEPROP 1 LAST LOCATION R4531
J 0
(-550 3475);
DISPLAY 0.787234 (-550 3475);
FORCEPROP 1 LASTPIN (-400 3475) $PN 1
J 0
(-388 3487);
DISPLAY 0.787234 (-388 3487);
PAINT MONO (-388 3487);
FORCEPROP 1 LASTPIN (-200 3475) $PN 2
J 0
(-238 3487);
DISPLAY 0.787234 (-238 3487);
PAINT MONO (-238 3487);
FORCEPROP 2 LAST CDS_LIB pure_quanta
J 0
(-300 3475);
DISPLAY INVISIBLE (-300 3475);
FORCEPROP 1 LAST PATH I296
J 0
(-350 3625);
DISPLAY 0.978723 (-350 3625);
PAINT WHITE (-350 3625);
DISPLAY INVISIBLE (-350 3625);
FORCEPROP 1 LAST WATTAGE 1/16W
J 2
(-125 3550);
DISPLAY 0.404255 (-125 3550);
DISPLAY INVISIBLE (-125 3550);
FORCEPROP 1 LAST PACK_TYPE 0402LF
J 0
(-50 3475);
DISPLAY 0.510638 (-50 3475);
DISPLAY INVISIBLE (-50 3475);
FORCEPROP 0 LAST $SEC 1
J 0
(-550 3525);
DISPLAY 0.680851 (-550 3525);
PAINT MONO (-550 3525);
DISPLAY INVISIBLE (-550 3525);
FORCEPROP 0 LAST CDS_SEC 1
J 0
(-550 3525);
DISPLAY 1.021277 (-550 3525);
DISPLAY INVISIBLE (-550 3525);
FORCEADD OFFPAGE..1
(-2250 6400);
FORCEPROP 2 LAST $XR2 213 
J 0
(-2742 6400);
DISPLAY 0.638298 (-2742 6400);
PAINT MONO (-2742 6400);
FORCEPROP 2 LAST $XR1 241 
J 0
(-2622 6400);
DISPLAY 0.638298 (-2622 6400);
PAINT MONO (-2622 6400);
FORCEPROP 2 LAST $XR0 131 
J 0
(-2502 6400);
DISPLAY 0.638298 (-2502 6400);
PAINT MONO (-2502 6400);
FORCEPROP 2 LAST PATH I299
J 0
(-2200 6475);
DISPLAY 1.021277 (-2200 6475);
DISPLAY INVISIBLE (-2200 6475);
FORCEPROP 1 LAST COMMENT_BODY TRUE
J 0
(-2125 6300);
DISPLAY 0.872340 (-2125 6300);
PAINT GREEN (-2125 6300);
DISPLAY INVISIBLE (-2125 6300);
FORCEPROP 1 LAST OFFPAGE TRUE
J 0
(-1925 6275);
DISPLAY 0.872340 (-1925 6275);
PAINT GREEN (-1925 6275);
DISPLAY INVISIBLE (-1925 6275);
FORCEPROP 2 LAST CDS_LIB standard
J 0
(-2250 6400);
DISPLAY INVISIBLE (-2250 6400);
FORCEADD Q_RES..1
(5000 6025);
FORCEPROP 1 LAST PART_NUMBER CS22002FB07
J 0
(4875 6075);
DISPLAY 0.638298 (4875 6075);
DISPLAY INVISIBLE (4875 6075);
FORCEPROP 1 LAST MATERIAL EMPTY
J 0
(5375 6025);
DISPLAY 0.638298 (5375 6025);
PAINT RED (5375 6025);
FORCEPROP 1 LAST VALUE 2K
J 2
(5225 6025);
DISPLAY 0.638298 (5225 6025);
FORCEPROP 1 LAST TOLERANCE 1%
J 0
(5275 6025);
DISPLAY 0.638298 (5275 6025);
FORCEPROP 1 LAST $LOCATION R3062
J 0
(4725 6025);
DISPLAY 0.638298 (4725 6025);
FORCEPROP 1 LASTPIN (4900 6025) $PN 1
J 0
(4912 6037);
DISPLAY 0.787234 (4912 6037);
FORCEPROP 1 LASTPIN (5100 6025) $PN 2
J 0
(5062 6037);
DISPLAY 0.787234 (5062 6037);
FORCEPROP 1 LAST PATH I3
J 0
(4950 6175);
DISPLAY 0.978723 (4950 6175);
PAINT WHITE (4950 6175);
DISPLAY INVISIBLE (4950 6175);
FORCEPROP 2 LAST CDS_LIB pure_quanta
J 0
(5000 6025);
PAINT MONO (5000 6025);
DISPLAY INVISIBLE (5000 6025);
FORCEPROP 1 LAST WATTAGE 1/16W
J 2
(5300 6125);
DISPLAY 0.638298 (5300 6125);
DISPLAY INVISIBLE (5300 6125);
FORCEPROP 1 LAST PACK_TYPE 0402LF
J 0
(4875 6125);
DISPLAY 0.638298 (4875 6125);
DISPLAY INVISIBLE (4875 6125);
FORCEPROP 2 LAST CDS_LOCATION R3062
J 0
(4950 6225);
DISPLAY 1.021277 (4950 6225);
DISPLAY INVISIBLE (4950 6225);
FORCEPROP 2 LAST $SEC 1
J 0
(4950 6225);
DISPLAY 0.680851 (4950 6225);
PAINT MONO (4950 6225);
DISPLAY INVISIBLE (4950 6225);
FORCEPROP 2 LAST CDS_SEC 1
J 0
(4950 6225);
DISPLAY 1.021277 (4950 6225);
DISPLAY INVISIBLE (4950 6225);
FORCEADD OFFPAGE..2
(5675 1750);
FORCEPROP 2 LAST $XR0 229 
J 0
(5864 1750);
DISPLAY 0.638298 (5864 1750);
PAINT MONO (5864 1750);
FORCEPROP 1 LAST OFFPAGE TRUE
J 0
(6000 1625);
DISPLAY 0.872340 (6000 1625);
PAINT GREEN (6000 1625);
DISPLAY INVISIBLE (6000 1625);
FORCEPROP 1 LAST COMMENT_BODY TRUE
J 0
(5630 1655);
DISPLAY 0.872340 (5630 1655);
PAINT GREEN (5630 1655);
DISPLAY INVISIBLE (5630 1655);
FORCEPROP 2 LAST CDS_LIB standard
J 0
(5675 1750);
PAINT MONO (5675 1750);
DISPLAY INVISIBLE (5675 1750);
FORCEPROP 2 LAST PATH I30
J 0
(5875 1800);
DISPLAY 1.021277 (5875 1800);
DISPLAY INVISIBLE (5875 1800);
FORCEADD OFFPAGE..3
R 2
(-2250 6350);
FORCEPROP 2 LAST $XR2 241 
J 0
(-2770 6350);
DISPLAY 0.638298 (-2770 6350);
PAINT MONO (-2770 6350);
FORCEPROP 2 LAST $XR1 213 
J 0
(-2650 6350);
DISPLAY 0.638298 (-2650 6350);
PAINT MONO (-2650 6350);
FORCEPROP 2 LAST $XR0 131 
J 0
(-2530 6350);
DISPLAY 0.638298 (-2530 6350);
PAINT MONO (-2530 6350);
FORCEPROP 2 LAST PATH I300
J 0
(-2200 6425);
DISPLAY 1.021277 (-2200 6425);
DISPLAY INVISIBLE (-2200 6425);
FORCEPROP 1 LAST OFFPAGE TRUE
J 2
(-2575 6225);
DISPLAY 0.872340 (-2575 6225);
DISPLAY INVISIBLE (-2575 6225);
FORCEPROP 1 LAST COMMENT_BODY TRUE
J 2
(-2200 6250);
DISPLAY 0.872340 (-2200 6250);
PAINT GREEN (-2200 6250);
DISPLAY INVISIBLE (-2200 6250);
FORCEPROP 2 LAST CDS_LIB standard
J 0
(-2250 6350);
DISPLAY INVISIBLE (-2250 6350);
FORCEADD OFFPAGE..2
(1400 6400);
FORCEPROP 2 LAST $XR0 241 
J 0
(1589 6400);
DISPLAY 0.638298 (1589 6400);
PAINT MONO (1589 6400);
FORCEPROP 2 LAST PATH I301
J 0
(1600 6450);
DISPLAY 1.021277 (1600 6450);
DISPLAY INVISIBLE (1600 6450);
FORCEPROP 2 LAST CDS_LIB standard
J 0
(1400 6400);
PAINT MONO (1400 6400);
DISPLAY INVISIBLE (1400 6400);
FORCEPROP 1 LAST OFFPAGE TRUE
J 0
(1725 6275);
DISPLAY 0.872340 (1725 6275);
PAINT GREEN (1725 6275);
DISPLAY INVISIBLE (1725 6275);
FORCEPROP 1 LAST COMMENT_BODY TRUE
J 0
(1355 6305);
DISPLAY 0.872340 (1355 6305);
PAINT GREEN (1355 6305);
DISPLAY INVISIBLE (1355 6305);
FORCEADD OFFPAGE..3
(1400 6350);
FORCEPROP 2 LAST $XR0 241 
J 0
(1614 6350);
DISPLAY 0.638298 (1614 6350);
PAINT MONO (1614 6350);
FORCEPROP 2 LAST PATH I302
J 0
(1625 6400);
DISPLAY 1.021277 (1625 6400);
DISPLAY INVISIBLE (1625 6400);
FORCEPROP 2 LAST CDS_LIB standard
J 0
(1400 6350);
PAINT MONO (1400 6350);
DISPLAY INVISIBLE (1400 6350);
FORCEPROP 1 LAST COMMENT_BODY TRUE
J 0
(1350 6250);
DISPLAY 0.872340 (1350 6250);
PAINT GREEN (1350 6250);
DISPLAY INVISIBLE (1350 6250);
FORCEPROP 1 LAST OFFPAGE TRUE
J 0
(1725 6225);
DISPLAY 0.872340 (1725 6225);
PAINT GREEN (1725 6225);
DISPLAY INVISIBLE (1725 6225);
FORCEADD Q_RES..1
(-350 6400);
FORCEPROP 1 LAST PART_NUMBER CS03322FB03
J 0
(-475 6475);
DISPLAY 0.510638 (-475 6475);
DISPLAY INVISIBLE (-475 6475);
FORCEPROP 1 LAST MATERIAL CHIP
J 0
(-50 6400);
DISPLAY 0.510638 (-50 6400);
FORCEPROP 1 LAST WATTAGE 1/16W
J 2
(-175 6525);
DISPLAY 0.510638 (-175 6525);
FORCEPROP 1 LAST TOLERANCE 1%
J 0
(-125 6400);
DISPLAY 0.510638 (-125 6400);
FORCEPROP 1 LAST PACK_TYPE 0402LF
J 0
(-475 6525);
DISPLAY 0.510638 (-475 6525);
FORCEPROP 1 LAST VALUE 33.2
J 2
(-150 6400);
DISPLAY 0.510638 (-150 6400);
FORCEPROP 1 LAST $LOCATION R577
J 0
(-625 6400);
DISPLAY 0.787234 (-625 6400);
FORCEPROP 1 LASTPIN (-450 6400) $PN 1
J 0
(-438 6412);
DISPLAY 0.787234 (-438 6412);
FORCEPROP 1 LASTPIN (-250 6400) $PN 2
J 0
(-288 6412);
DISPLAY 0.787234 (-288 6412);
FORCEPROP 1 LAST PATH I303
J 0
(-400 6550);
DISPLAY 0.978723 (-400 6550);
PAINT WHITE (-400 6550);
DISPLAY INVISIBLE (-400 6550);
FORCEPROP 2 LAST CDS_LIB pure_quanta
J 0
(-350 6400);
PAINT MONO (-350 6400);
DISPLAY INVISIBLE (-350 6400);
FORCEPROP 2 LAST CDS_LOCATION R577
J 0
(-400 6600);
DISPLAY 1.021277 (-400 6600);
DISPLAY INVISIBLE (-400 6600);
FORCEPROP 2 LAST $SEC 1
J 0
(-400 6600);
DISPLAY 0.680851 (-400 6600);
PAINT MONO (-400 6600);
DISPLAY INVISIBLE (-400 6600);
FORCEPROP 2 LAST CDS_SEC 1
J 0
(-400 6600);
DISPLAY 1.021277 (-400 6600);
DISPLAY INVISIBLE (-400 6600);
FORCEADD Q_RES..1
(-350 6350);
FORCEPROP 1 LAST PART_NUMBER CS03322FB03
J 0
(-475 6400);
DISPLAY 0.638298 (-475 6400);
DISPLAY INVISIBLE (-475 6400);
FORCEPROP 1 LAST MATERIAL CHIP
J 0
(-50 6350);
DISPLAY 0.510638 (-50 6350);
FORCEPROP 1 LAST TOLERANCE 1%
J 0
(-125 6350);
DISPLAY 0.510638 (-125 6350);
FORCEPROP 1 LAST VALUE 33.2
J 2
(-150 6350);
DISPLAY 0.510638 (-150 6350);
FORCEPROP 1 LAST $LOCATION R578
J 0
(-625 6350);
DISPLAY 0.787234 (-625 6350);
FORCEPROP 1 LASTPIN (-450 6350) $PN 1
J 0
(-438 6362);
DISPLAY 0.787234 (-438 6362);
FORCEPROP 1 LASTPIN (-250 6350) $PN 2
J 0
(-288 6362);
DISPLAY 0.787234 (-288 6362);
FORCEPROP 1 LAST PATH I304
J 0
(-400 6500);
DISPLAY 0.978723 (-400 6500);
PAINT WHITE (-400 6500);
DISPLAY INVISIBLE (-400 6500);
FORCEPROP 1 LAST PACK_TYPE 0402LF
J 0
(0 6350);
DISPLAY 0.638298 (0 6350);
DISPLAY INVISIBLE (0 6350);
FORCEPROP 2 LAST CDS_LIB pure_quanta
J 0
(-350 6350);
PAINT MONO (-350 6350);
DISPLAY INVISIBLE (-350 6350);
FORCEPROP 1 LAST WATTAGE 1/16W
J 2
(-150 6450);
DISPLAY 0.638298 (-150 6450);
DISPLAY INVISIBLE (-150 6450);
FORCEPROP 2 LAST CDS_LOCATION R578
J 0
(-400 6550);
DISPLAY 1.021277 (-400 6550);
DISPLAY INVISIBLE (-400 6550);
FORCEPROP 2 LAST $SEC 1
J 0
(-400 6550);
DISPLAY 0.680851 (-400 6550);
PAINT MONO (-400 6550);
DISPLAY INVISIBLE (-400 6550);
FORCEPROP 2 LAST CDS_SEC 1
J 0
(-400 6550);
DISPLAY 1.021277 (-400 6550);
DISPLAY INVISIBLE (-400 6550);
FORCEADD Q_RES..1
(-1225 6050);
FORCEPROP 1 LAST PART_NUMBER CS03322FB03
J 0
(-1350 6125);
DISPLAY 0.510638 (-1350 6125);
DISPLAY INVISIBLE (-1350 6125);
FORCEPROP 1 LAST WATTAGE 1/16W
J 2
(-1050 6175);
DISPLAY 0.510638 (-1050 6175);
FORCEPROP 1 LAST VALUE 33.2
J 2
(-1025 6050);
DISPLAY 0.510638 (-1025 6050);
FORCEPROP 1 LAST TOLERANCE 1%
J 0
(-1000 6050);
DISPLAY 0.510638 (-1000 6050);
FORCEPROP 1 LAST MATERIAL CHIP
J 0
(-925 6050);
DISPLAY 0.510638 (-925 6050);
FORCEPROP 1 LAST PACK_TYPE 0402LF
J 0
(-1350 6175);
DISPLAY 0.510638 (-1350 6175);
FORCEPROP 1 LAST $LOCATION R4512
J 0
(-1400 6050);
DISPLAY 0.638298 (-1400 6050);
FORCEPROP 1 LASTPIN (-1325 6050) $PN 1
J 0
(-1313 6062);
DISPLAY 0.787234 (-1313 6062);
PAINT MONO (-1313 6062);
FORCEPROP 1 LASTPIN (-1125 6050) $PN 2
J 0
(-1163 6062);
DISPLAY 0.787234 (-1163 6062);
PAINT MONO (-1163 6062);
FORCEPROP 2 LAST CDS_LIB pure_quanta
J 0
(-1225 6050);
DISPLAY INVISIBLE (-1225 6050);
FORCEPROP 1 LAST PATH I305
J 0
(-1275 6200);
DISPLAY 0.978723 (-1275 6200);
PAINT WHITE (-1275 6200);
DISPLAY INVISIBLE (-1275 6200);
FORCEPROP 0 LAST CDS_LOCATION R4512
J 0
(-1050 6200);
DISPLAY 1.021277 (-1050 6200);
DISPLAY INVISIBLE (-1050 6200);
FORCEPROP 0 LAST $SEC 1
J 0
(-1050 6200);
DISPLAY 0.680851 (-1050 6200);
PAINT MONO (-1050 6200);
DISPLAY INVISIBLE (-1050 6200);
FORCEPROP 0 LAST CDS_SEC 1
J 0
(-1050 6200);
DISPLAY 1.021277 (-1050 6200);
DISPLAY INVISIBLE (-1050 6200);
FORCEADD Q_RES..1
(-1225 6000);
FORCEPROP 1 LAST PART_NUMBER CS00002JB13
J 0
(-1275 6050);
DISPLAY 0.404255 (-1275 6050);
DISPLAY INVISIBLE (-1275 6050);
FORCEPROP 1 LAST VALUE 0
J 2
(-1025 6000);
DISPLAY 0.510638 (-1025 6000);
FORCEPROP 1 LAST TOLERANCE 5%
J 0
(-1000 6000);
DISPLAY 0.510638 (-1000 6000);
FORCEPROP 1 LAST MATERIAL CHIP
J 0
(-925 6000);
DISPLAY 0.510638 (-925 6000);
FORCEPROP 1 LAST $LOCATION R4513
J 0
(-1400 6000);
DISPLAY 0.638298 (-1400 6000);
FORCEPROP 1 LASTPIN (-1325 6000) $PN 1
J 0
(-1313 6012);
DISPLAY 0.787234 (-1313 6012);
PAINT MONO (-1313 6012);
FORCEPROP 1 LASTPIN (-1125 6000) $PN 2
J 0
(-1163 6012);
DISPLAY 0.787234 (-1163 6012);
PAINT MONO (-1163 6012);
FORCEPROP 2 LAST CDS_LIB pure_quanta
J 0
(-1225 6000);
DISPLAY INVISIBLE (-1225 6000);
FORCEPROP 1 LAST PACK_TYPE 0402LF
J 0
(-975 6000);
DISPLAY 0.510638 (-975 6000);
DISPLAY INVISIBLE (-975 6000);
FORCEPROP 1 LAST WATTAGE 1/16W
J 2
(-1050 6075);
DISPLAY 0.404255 (-1050 6075);
DISPLAY INVISIBLE (-1050 6075);
FORCEPROP 1 LAST PATH I306
J 0
(-1275 6150);
DISPLAY 0.978723 (-1275 6150);
PAINT WHITE (-1275 6150);
DISPLAY INVISIBLE (-1275 6150);
FORCEPROP 0 LAST CDS_LOCATION R4513
J 0
(-1400 6050);
DISPLAY 1.021277 (-1400 6050);
DISPLAY INVISIBLE (-1400 6050);
FORCEPROP 0 LAST $SEC 1
J 0
(-1400 6050);
DISPLAY 0.680851 (-1400 6050);
PAINT MONO (-1400 6050);
DISPLAY INVISIBLE (-1400 6050);
FORCEPROP 0 LAST CDS_SEC 1
J 0
(-1400 6050);
DISPLAY 1.021277 (-1400 6050);
DISPLAY INVISIBLE (-1400 6050);
FORCEADD OFFPAGE..1
(-2250 6050);
FORCEPROP 2 LAST $XR1 241 
J 0
(-2622 6050);
DISPLAY 0.638298 (-2622 6050);
PAINT MONO (-2622 6050);
FORCEPROP 2 LAST $XR0 240 
J 0
(-2502 6050);
DISPLAY 0.638298 (-2502 6050);
PAINT MONO (-2502 6050);
FORCEPROP 2 LAST PATH I307
J 0
(-2200 6125);
DISPLAY 1.021277 (-2200 6125);
DISPLAY INVISIBLE (-2200 6125);
FORCEPROP 2 LAST CDS_LIB standard
J 0
(-2250 6050);
DISPLAY INVISIBLE (-2250 6050);
FORCEPROP 1 LAST OFFPAGE TRUE
J 0
(-1925 5925);
DISPLAY 0.872340 (-1925 5925);
PAINT GREEN (-1925 5925);
DISPLAY INVISIBLE (-1925 5925);
FORCEPROP 1 LAST COMMENT_BODY TRUE
J 0
(-2125 5950);
DISPLAY 0.872340 (-2125 5950);
PAINT GREEN (-2125 5950);
DISPLAY INVISIBLE (-2125 5950);
FORCEADD OFFPAGE..3
R 2
(-2250 6000);
FORCEPROP 2 LAST $XR1 241 
J 0
(-2650 6000);
DISPLAY 0.638298 (-2650 6000);
PAINT MONO (-2650 6000);
FORCEPROP 2 LAST $XR0 240 
J 0
(-2530 6000);
DISPLAY 0.638298 (-2530 6000);
PAINT MONO (-2530 6000);
FORCEPROP 2 LAST CDS_LIB standard
J 0
(-2250 6000);
DISPLAY INVISIBLE (-2250 6000);
FORCEPROP 1 LAST COMMENT_BODY TRUE
J 2
(-2200 5900);
DISPLAY 0.872340 (-2200 5900);
PAINT GREEN (-2200 5900);
DISPLAY INVISIBLE (-2200 5900);
FORCEPROP 1 LAST OFFPAGE TRUE
J 2
(-2575 5875);
DISPLAY 0.872340 (-2575 5875);
DISPLAY INVISIBLE (-2575 5875);
FORCEPROP 2 LAST PATH I308
J 0
(-2200 6075);
DISPLAY 1.021277 (-2200 6075);
DISPLAY INVISIBLE (-2200 6075);
FORCEADD OFFPAGE..2
(1350 6050);
FORCEPROP 2 LAST $XR0 228 
J 0
(1539 6050);
DISPLAY 0.638298 (1539 6050);
PAINT MONO (1539 6050);
FORCEPROP 2 LAST CDS_LIB standard
J 0
(1350 6050);
DISPLAY INVISIBLE (1350 6050);
FORCEPROP 2 LAST PATH I309
J 0
(1525 6125);
DISPLAY 1.021277 (1525 6125);
DISPLAY INVISIBLE (1525 6125);
FORCEPROP 1 LAST OFFPAGE TRUE
J 0
(1675 5925);
DISPLAY 0.872340 (1675 5925);
PAINT GREEN (1675 5925);
DISPLAY INVISIBLE (1675 5925);
FORCEPROP 1 LAST COMMENT_BODY TRUE
J 0
(1305 5955);
DISPLAY 0.872340 (1305 5955);
PAINT GREEN (1305 5955);
DISPLAY INVISIBLE (1305 5955);
FORCEADD OFFPAGE..3
(5675 1700);
FORCEPROP 2 LAST $XR0 229 
J 0
(5889 1700);
DISPLAY 0.638298 (5889 1700);
PAINT MONO (5889 1700);
FORCEPROP 1 LAST COMMENT_BODY TRUE
J 0
(5625 1600);
DISPLAY 0.872340 (5625 1600);
PAINT GREEN (5625 1600);
DISPLAY INVISIBLE (5625 1600);
FORCEPROP 1 LAST OFFPAGE TRUE
J 0
(6000 1575);
DISPLAY 0.872340 (6000 1575);
PAINT GREEN (6000 1575);
DISPLAY INVISIBLE (6000 1575);
FORCEPROP 2 LAST CDS_LIB standard
J 0
(5675 1700);
PAINT MONO (5675 1700);
DISPLAY INVISIBLE (5675 1700);
FORCEPROP 2 LAST PATH I31
J 0
(5900 1750);
DISPLAY 1.021277 (5900 1750);
DISPLAY INVISIBLE (5900 1750);
FORCEADD OFFPAGE..3
(1350 6000);
FORCEPROP 2 LAST $XR0 228 
J 0
(1564 6000);
DISPLAY 0.638298 (1564 6000);
PAINT MONO (1564 6000);
FORCEPROP 2 LAST CDS_LIB standard
J 0
(1350 6000);
DISPLAY INVISIBLE (1350 6000);
FORCEPROP 2 LAST PATH I310
J 0
(1550 6075);
DISPLAY 1.021277 (1550 6075);
DISPLAY INVISIBLE (1550 6075);
FORCEPROP 1 LAST COMMENT_BODY TRUE
J 0
(1300 5900);
DISPLAY 0.872340 (1300 5900);
PAINT GREEN (1300 5900);
DISPLAY INVISIBLE (1300 5900);
FORCEPROP 1 LAST OFFPAGE TRUE
J 0
(1675 5875);
DISPLAY 0.872340 (1675 5875);
PAINT GREEN (1675 5875);
DISPLAY INVISIBLE (1675 5875);
FORCEADD Q_RES..1
(3875 2050);
FORCEPROP 1 LAST PART_NUMBER CS00002JB13
J 0
(3825 2100);
DISPLAY 0.404255 (3825 2100);
DISPLAY INVISIBLE (3825 2100);
FORCEPROP 1 LAST TOLERANCE 5%
J 0
(4100 2050);
DISPLAY 0.510638 (4100 2050);
FORCEPROP 1 LAST VALUE 0
J 2
(4075 2050);
DISPLAY 0.510638 (4075 2050);
FORCEPROP 1 LAST MATERIAL CHIP
J 0
(4175 2050);
DISPLAY 0.510638 (4175 2050);
FORCEPROP 1 LAST LOCATION R593
J 0
(3575 2050);
DISPLAY 0.787234 (3575 2050);
FORCEPROP 1 LASTPIN (3775 2050) $PN 1
J 0
(3787 2062);
DISPLAY 0.787234 (3787 2062);
PAINT MONO (3787 2062);
FORCEPROP 1 LASTPIN (3975 2050) $PN 2
J 0
(3937 2062);
DISPLAY 0.787234 (3937 2062);
PAINT MONO (3937 2062);
FORCEPROP 1 LAST WATTAGE 1/16W
J 2
(4050 2125);
DISPLAY 0.404255 (4050 2125);
DISPLAY INVISIBLE (4050 2125);
FORCEPROP 1 LAST PACK_TYPE 0402LF
J 0
(4125 2050);
DISPLAY 0.510638 (4125 2050);
DISPLAY INVISIBLE (4125 2050);
FORCEPROP 2 LAST CDS_LIB pure_quanta
J 0
(3875 2050);
DISPLAY INVISIBLE (3875 2050);
FORCEPROP 1 LAST PATH I311
J 0
(3825 2200);
DISPLAY 0.978723 (3825 2200);
PAINT WHITE (3825 2200);
DISPLAY INVISIBLE (3825 2200);
FORCEPROP 0 LAST $SEC 1
J 0
(3575 2100);
DISPLAY 0.680851 (3575 2100);
PAINT MONO (3575 2100);
DISPLAY INVISIBLE (3575 2100);
FORCEPROP 0 LAST CDS_SEC 1
J 0
(3575 2100);
DISPLAY 1.021277 (3575 2100);
DISPLAY INVISIBLE (3575 2100);
FORCEADD Q_RES..1
(3875 2000);
FORCEPROP 1 LAST PART_NUMBER CS00002JB13
J 0
(3825 2050);
DISPLAY 0.404255 (3825 2050);
DISPLAY INVISIBLE (3825 2050);
FORCEPROP 1 LAST TOLERANCE 5%
J 0
(4100 2000);
DISPLAY 0.510638 (4100 2000);
FORCEPROP 1 LAST VALUE 0
J 2
(4075 2000);
DISPLAY 0.510638 (4075 2000);
FORCEPROP 1 LAST MATERIAL CHIP
J 0
(4175 2000);
DISPLAY 0.510638 (4175 2000);
FORCEPROP 1 LAST LOCATION R594
J 0
(3575 2000);
DISPLAY 0.787234 (3575 2000);
FORCEPROP 1 LASTPIN (3775 2000) $PN 1
J 0
(3787 2012);
DISPLAY 0.787234 (3787 2012);
PAINT MONO (3787 2012);
FORCEPROP 1 LASTPIN (3975 2000) $PN 2
J 0
(3937 2012);
DISPLAY 0.787234 (3937 2012);
PAINT MONO (3937 2012);
FORCEPROP 1 LAST WATTAGE 1/16W
J 2
(4050 2075);
DISPLAY 0.404255 (4050 2075);
DISPLAY INVISIBLE (4050 2075);
FORCEPROP 1 LAST PACK_TYPE 0402LF
J 0
(4125 2000);
DISPLAY 0.510638 (4125 2000);
DISPLAY INVISIBLE (4125 2000);
FORCEPROP 2 LAST CDS_LIB pure_quanta
J 0
(3875 2000);
DISPLAY INVISIBLE (3875 2000);
FORCEPROP 1 LAST PATH I312
J 0
(3825 2150);
DISPLAY 0.978723 (3825 2150);
PAINT WHITE (3825 2150);
DISPLAY INVISIBLE (3825 2150);
FORCEPROP 0 LAST $SEC 1
J 0
(3575 2050);
DISPLAY 0.680851 (3575 2050);
PAINT MONO (3575 2050);
DISPLAY INVISIBLE (3575 2050);
FORCEPROP 0 LAST CDS_SEC 1
J 0
(3575 2050);
DISPLAY 1.021277 (3575 2050);
DISPLAY INVISIBLE (3575 2050);
FORCEADD Q_RES..1
(3875 1700);
FORCEPROP 1 LAST PART_NUMBER CS00002JB13
J 0
(3825 1750);
DISPLAY 0.404255 (3825 1750);
DISPLAY INVISIBLE (3825 1750);
FORCEPROP 1 LAST MATERIAL CHIP
J 0
(4175 1700);
DISPLAY 0.510638 (4175 1700);
FORCEPROP 1 LAST VALUE 0
J 2
(4075 1700);
DISPLAY 0.510638 (4075 1700);
FORCEPROP 1 LAST TOLERANCE 5%
J 0
(4100 1700);
DISPLAY 0.510638 (4100 1700);
FORCEPROP 1 LAST LOCATION R596
J 0
(3575 1700);
DISPLAY 0.787234 (3575 1700);
FORCEPROP 1 LASTPIN (3775 1700) $PN 1
J 0
(3787 1712);
DISPLAY 0.787234 (3787 1712);
PAINT MONO (3787 1712);
FORCEPROP 1 LASTPIN (3975 1700) $PN 2
J 0
(3937 1712);
DISPLAY 0.787234 (3937 1712);
PAINT MONO (3937 1712);
FORCEPROP 2 LAST CDS_LIB pure_quanta
J 0
(3875 1700);
DISPLAY INVISIBLE (3875 1700);
FORCEPROP 1 LAST PACK_TYPE 0402LF
J 0
(4125 1700);
DISPLAY 0.510638 (4125 1700);
DISPLAY INVISIBLE (4125 1700);
FORCEPROP 1 LAST WATTAGE 1/16W
J 2
(4050 1775);
DISPLAY 0.404255 (4050 1775);
DISPLAY INVISIBLE (4050 1775);
FORCEPROP 1 LAST PATH I313
J 0
(3825 1850);
DISPLAY 0.978723 (3825 1850);
PAINT WHITE (3825 1850);
DISPLAY INVISIBLE (3825 1850);
FORCEPROP 0 LAST $SEC 1
J 0
(3575 1750);
DISPLAY 0.680851 (3575 1750);
PAINT MONO (3575 1750);
DISPLAY INVISIBLE (3575 1750);
FORCEPROP 0 LAST CDS_SEC 1
J 0
(3575 1750);
DISPLAY 1.021277 (3575 1750);
DISPLAY INVISIBLE (3575 1750);
FORCEADD Q_RES..1
(3875 1750);
FORCEPROP 1 LAST PART_NUMBER CS00002JB13
J 0
(3825 1800);
DISPLAY 0.404255 (3825 1800);
DISPLAY INVISIBLE (3825 1800);
FORCEPROP 1 LAST MATERIAL CHIP
J 0
(4175 1750);
DISPLAY 0.510638 (4175 1750);
FORCEPROP 1 LAST VALUE 0
J 2
(4075 1750);
DISPLAY 0.510638 (4075 1750);
FORCEPROP 1 LAST TOLERANCE 5%
J 0
(4100 1750);
DISPLAY 0.510638 (4100 1750);
FORCEPROP 1 LAST LOCATION R595
J 0
(3575 1750);
DISPLAY 0.787234 (3575 1750);
FORCEPROP 1 LASTPIN (3775 1750) $PN 1
J 0
(3787 1762);
DISPLAY 0.787234 (3787 1762);
PAINT MONO (3787 1762);
FORCEPROP 1 LASTPIN (3975 1750) $PN 2
J 0
(3937 1762);
DISPLAY 0.787234 (3937 1762);
PAINT MONO (3937 1762);
FORCEPROP 2 LAST CDS_LIB pure_quanta
J 0
(3875 1750);
DISPLAY INVISIBLE (3875 1750);
FORCEPROP 1 LAST PACK_TYPE 0402LF
J 0
(4125 1750);
DISPLAY 0.510638 (4125 1750);
DISPLAY INVISIBLE (4125 1750);
FORCEPROP 1 LAST WATTAGE 1/16W
J 2
(4050 1825);
DISPLAY 0.404255 (4050 1825);
DISPLAY INVISIBLE (4050 1825);
FORCEPROP 1 LAST PATH I314
J 0
(3825 1900);
DISPLAY 0.978723 (3825 1900);
PAINT WHITE (3825 1900);
DISPLAY INVISIBLE (3825 1900);
FORCEPROP 0 LAST $SEC 1
J 0
(3575 1800);
DISPLAY 0.680851 (3575 1800);
PAINT MONO (3575 1800);
DISPLAY INVISIBLE (3575 1800);
FORCEPROP 0 LAST CDS_SEC 1
J 0
(3575 1800);
DISPLAY 1.021277 (3575 1800);
DISPLAY INVISIBLE (3575 1800);
FORCEADD Q_RES..1
(3875 1375);
FORCEPROP 1 LAST PART_NUMBER CS00002JB13
J 0
(3825 1425);
DISPLAY 0.404255 (3825 1425);
DISPLAY INVISIBLE (3825 1425);
FORCEPROP 1 LAST TOLERANCE 5%
J 0
(4100 1375);
DISPLAY 0.510638 (4100 1375);
FORCEPROP 1 LAST MATERIAL CHIP
J 0
(4175 1375);
DISPLAY 0.510638 (4175 1375);
FORCEPROP 1 LAST VALUE 0
J 2
(4075 1375);
DISPLAY 0.510638 (4075 1375);
FORCEPROP 1 LAST LOCATION R598
J 0
(3575 1375);
DISPLAY 0.787234 (3575 1375);
FORCEPROP 1 LASTPIN (3775 1375) $PN 1
J 0
(3787 1387);
DISPLAY 0.787234 (3787 1387);
PAINT MONO (3787 1387);
FORCEPROP 1 LASTPIN (3975 1375) $PN 2
J 0
(3937 1387);
DISPLAY 0.787234 (3937 1387);
PAINT MONO (3937 1387);
FORCEPROP 1 LAST PATH I315
J 0
(3825 1525);
DISPLAY 0.978723 (3825 1525);
PAINT WHITE (3825 1525);
DISPLAY INVISIBLE (3825 1525);
FORCEPROP 2 LAST CDS_LIB pure_quanta
J 0
(3875 1375);
DISPLAY INVISIBLE (3875 1375);
FORCEPROP 1 LAST PACK_TYPE 0402LF
J 0
(4125 1375);
DISPLAY 0.510638 (4125 1375);
DISPLAY INVISIBLE (4125 1375);
FORCEPROP 1 LAST WATTAGE 1/16W
J 2
(4050 1450);
DISPLAY 0.404255 (4050 1450);
DISPLAY INVISIBLE (4050 1450);
FORCEPROP 0 LAST $SEC 1
J 0
(3575 1425);
DISPLAY 0.680851 (3575 1425);
PAINT MONO (3575 1425);
DISPLAY INVISIBLE (3575 1425);
FORCEPROP 0 LAST CDS_SEC 1
J 0
(3575 1425);
DISPLAY 1.021277 (3575 1425);
DISPLAY INVISIBLE (3575 1425);
FORCEADD Q_RES..1
(3875 1425);
FORCEPROP 1 LAST PART_NUMBER CS00002JB13
J 0
(3825 1475);
DISPLAY 0.404255 (3825 1475);
DISPLAY INVISIBLE (3825 1475);
FORCEPROP 1 LAST MATERIAL CHIP
J 0
(4175 1425);
DISPLAY 0.510638 (4175 1425);
FORCEPROP 1 LAST VALUE 0
J 2
(4075 1425);
DISPLAY 0.510638 (4075 1425);
FORCEPROP 1 LAST TOLERANCE 5%
J 0
(4100 1425);
DISPLAY 0.510638 (4100 1425);
FORCEPROP 1 LAST LOCATION R597
J 0
(3575 1425);
DISPLAY 0.787234 (3575 1425);
FORCEPROP 1 LASTPIN (3775 1425) $PN 1
J 0
(3787 1437);
DISPLAY 0.787234 (3787 1437);
PAINT MONO (3787 1437);
FORCEPROP 1 LASTPIN (3975 1425) $PN 2
J 0
(3937 1437);
DISPLAY 0.787234 (3937 1437);
PAINT MONO (3937 1437);
FORCEPROP 1 LAST PATH I316
J 0
(3825 1575);
DISPLAY 0.978723 (3825 1575);
PAINT WHITE (3825 1575);
DISPLAY INVISIBLE (3825 1575);
FORCEPROP 2 LAST CDS_LIB pure_quanta
J 0
(3875 1425);
DISPLAY INVISIBLE (3875 1425);
FORCEPROP 1 LAST PACK_TYPE 0402LF
J 0
(4125 1425);
DISPLAY 0.510638 (4125 1425);
DISPLAY INVISIBLE (4125 1425);
FORCEPROP 1 LAST WATTAGE 1/16W
J 2
(4050 1500);
DISPLAY 0.404255 (4050 1500);
DISPLAY INVISIBLE (4050 1500);
FORCEPROP 0 LAST $SEC 1
J 0
(3575 1475);
DISPLAY 0.680851 (3575 1475);
PAINT MONO (3575 1475);
DISPLAY INVISIBLE (3575 1475);
FORCEPROP 0 LAST CDS_SEC 1
J 0
(3575 1475);
DISPLAY 1.021277 (3575 1475);
DISPLAY INVISIBLE (3575 1475);
FORCEADD Q_RES..1
(3875 1125);
FORCEPROP 1 LAST PART_NUMBER CS00002JB13
J 0
(3825 1175);
DISPLAY 0.404255 (3825 1175);
DISPLAY INVISIBLE (3825 1175);
FORCEPROP 1 LAST TOLERANCE 5%
J 0
(4100 1125);
DISPLAY 0.510638 (4100 1125);
FORCEPROP 1 LAST VALUE 0
J 2
(4075 1125);
DISPLAY 0.510638 (4075 1125);
FORCEPROP 1 LAST MATERIAL CHIP
J 0
(4175 1125);
DISPLAY 0.510638 (4175 1125);
FORCEPROP 1 LAST LOCATION R599
J 0
(3575 1125);
DISPLAY 0.787234 (3575 1125);
FORCEPROP 1 LASTPIN (3775 1125) $PN 1
J 0
(3787 1137);
DISPLAY 0.787234 (3787 1137);
PAINT MONO (3787 1137);
FORCEPROP 1 LASTPIN (3975 1125) $PN 2
J 0
(3937 1137);
DISPLAY 0.787234 (3937 1137);
PAINT MONO (3937 1137);
FORCEPROP 1 LAST PATH I317
J 0
(3825 1275);
DISPLAY 0.978723 (3825 1275);
PAINT WHITE (3825 1275);
DISPLAY INVISIBLE (3825 1275);
FORCEPROP 1 LAST WATTAGE 1/16W
J 2
(4050 1200);
DISPLAY 0.404255 (4050 1200);
DISPLAY INVISIBLE (4050 1200);
FORCEPROP 1 LAST PACK_TYPE 0402LF
J 0
(4125 1125);
DISPLAY 0.510638 (4125 1125);
DISPLAY INVISIBLE (4125 1125);
FORCEPROP 2 LAST CDS_LIB pure_quanta
J 0
(3875 1125);
DISPLAY INVISIBLE (3875 1125);
FORCEPROP 0 LAST $SEC 1
J 0
(3575 1175);
DISPLAY 0.680851 (3575 1175);
PAINT MONO (3575 1175);
DISPLAY INVISIBLE (3575 1175);
FORCEPROP 0 LAST CDS_SEC 1
J 0
(3575 1175);
DISPLAY 1.021277 (3575 1175);
DISPLAY INVISIBLE (3575 1175);
FORCEADD Q_RES..1
(3875 1075);
FORCEPROP 1 LAST PART_NUMBER CS00002JB13
J 0
(3825 1125);
DISPLAY 0.404255 (3825 1125);
DISPLAY INVISIBLE (3825 1125);
FORCEPROP 1 LAST TOLERANCE 5%
J 0
(4100 1075);
DISPLAY 0.510638 (4100 1075);
FORCEPROP 1 LAST VALUE 0
J 2
(4075 1075);
DISPLAY 0.510638 (4075 1075);
FORCEPROP 1 LAST MATERIAL CHIP
J 0
(4175 1075);
DISPLAY 0.510638 (4175 1075);
FORCEPROP 1 LAST LOCATION R600
J 0
(3575 1075);
DISPLAY 0.787234 (3575 1075);
FORCEPROP 1 LASTPIN (3775 1075) $PN 1
J 0
(3787 1087);
DISPLAY 0.787234 (3787 1087);
PAINT MONO (3787 1087);
FORCEPROP 1 LASTPIN (3975 1075) $PN 2
J 0
(3937 1087);
DISPLAY 0.787234 (3937 1087);
PAINT MONO (3937 1087);
FORCEPROP 1 LAST PATH I318
J 0
(3825 1225);
DISPLAY 0.978723 (3825 1225);
PAINT WHITE (3825 1225);
DISPLAY INVISIBLE (3825 1225);
FORCEPROP 1 LAST WATTAGE 1/16W
J 2
(4050 1150);
DISPLAY 0.404255 (4050 1150);
DISPLAY INVISIBLE (4050 1150);
FORCEPROP 1 LAST PACK_TYPE 0402LF
J 0
(4125 1075);
DISPLAY 0.510638 (4125 1075);
DISPLAY INVISIBLE (4125 1075);
FORCEPROP 2 LAST CDS_LIB pure_quanta
J 0
(3875 1075);
DISPLAY INVISIBLE (3875 1075);
FORCEPROP 0 LAST $SEC 1
J 0
(3575 1125);
DISPLAY 0.680851 (3575 1125);
PAINT MONO (3575 1125);
DISPLAY INVISIBLE (3575 1125);
FORCEPROP 0 LAST CDS_SEC 1
J 0
(3575 1125);
DISPLAY 1.021277 (3575 1125);
DISPLAY INVISIBLE (3575 1125);
FORCEADD OFFPAGE..2
(5675 1425);
FORCEPROP 2 LAST $XR0 230 
J 0
(5864 1425);
DISPLAY 0.638298 (5864 1425);
PAINT MONO (5864 1425);
FORCEPROP 1 LAST OFFPAGE TRUE
J 0
(6000 1300);
DISPLAY 0.872340 (6000 1300);
PAINT GREEN (6000 1300);
DISPLAY INVISIBLE (6000 1300);
FORCEPROP 1 LAST COMMENT_BODY TRUE
J 0
(5630 1330);
DISPLAY 0.872340 (5630 1330);
PAINT GREEN (5630 1330);
DISPLAY INVISIBLE (5630 1330);
FORCEPROP 2 LAST CDS_LIB standard
J 0
(5675 1425);
PAINT MONO (5675 1425);
DISPLAY INVISIBLE (5675 1425);
FORCEPROP 2 LAST PATH I32
J 0
(5875 1475);
DISPLAY 1.021277 (5875 1475);
DISPLAY INVISIBLE (5875 1475);
FORCEADD OFFPAGE..3
(5675 1375);
FORCEPROP 2 LAST $XR0 230 
J 0
(5889 1375);
DISPLAY 0.638298 (5889 1375);
PAINT MONO (5889 1375);
FORCEPROP 1 LAST COMMENT_BODY TRUE
J 0
(5625 1275);
DISPLAY 0.872340 (5625 1275);
PAINT GREEN (5625 1275);
DISPLAY INVISIBLE (5625 1275);
FORCEPROP 1 LAST OFFPAGE TRUE
J 0
(6000 1250);
DISPLAY 0.872340 (6000 1250);
PAINT GREEN (6000 1250);
DISPLAY INVISIBLE (6000 1250);
FORCEPROP 2 LAST CDS_LIB standard
J 0
(5675 1375);
PAINT MONO (5675 1375);
DISPLAY INVISIBLE (5675 1375);
FORCEPROP 2 LAST PATH I33
J 0
(5900 1425);
DISPLAY 1.021277 (5900 1425);
DISPLAY INVISIBLE (5900 1425);
FORCEADD OFFPAGE..2
(5675 1125);
FORCEPROP 2 LAST $XR0 230 
J 0
(5864 1125);
DISPLAY 0.638298 (5864 1125);
PAINT MONO (5864 1125);
FORCEPROP 1 LAST OFFPAGE TRUE
J 0
(6000 1000);
DISPLAY 0.872340 (6000 1000);
PAINT GREEN (6000 1000);
DISPLAY INVISIBLE (6000 1000);
FORCEPROP 1 LAST COMMENT_BODY TRUE
J 0
(5630 1030);
DISPLAY 0.872340 (5630 1030);
PAINT GREEN (5630 1030);
DISPLAY INVISIBLE (5630 1030);
FORCEPROP 2 LAST CDS_LIB standard
J 0
(5675 1125);
PAINT MONO (5675 1125);
DISPLAY INVISIBLE (5675 1125);
FORCEPROP 2 LAST PATH I34
J 0
(5875 1175);
DISPLAY 1.021277 (5875 1175);
DISPLAY INVISIBLE (5875 1175);
FORCEADD OFFPAGE..3
(5675 1075);
FORCEPROP 2 LAST $XR0 230 
J 0
(5889 1075);
DISPLAY 0.638298 (5889 1075);
PAINT MONO (5889 1075);
FORCEPROP 1 LAST COMMENT_BODY TRUE
J 0
(5625 975);
DISPLAY 0.872340 (5625 975);
PAINT GREEN (5625 975);
DISPLAY INVISIBLE (5625 975);
FORCEPROP 1 LAST OFFPAGE TRUE
J 0
(6000 950);
DISPLAY 0.872340 (6000 950);
PAINT GREEN (6000 950);
DISPLAY INVISIBLE (6000 950);
FORCEPROP 2 LAST CDS_LIB standard
J 0
(5675 1075);
PAINT MONO (5675 1075);
DISPLAY INVISIBLE (5675 1075);
FORCEPROP 2 LAST PATH I35
J 0
(5900 1125);
DISPLAY 1.021277 (5900 1125);
DISPLAY INVISIBLE (5900 1125);
FORCEADD Q_RES..1
(-200 5800);
FORCEPROP 1 LAST PART_NUMBER CS03322FB03
J 0
(-325 5875);
DISPLAY 0.510638 (-325 5875);
DISPLAY INVISIBLE (-325 5875);
FORCEPROP 1 LAST WATTAGE 1/16W
J 2
(-25 5925);
DISPLAY 0.510638 (-25 5925);
FORCEPROP 1 LAST TOLERANCE 1%
J 0
(25 5800);
DISPLAY 0.510638 (25 5800);
FORCEPROP 1 LAST MATERIAL CHIP
J 0
(100 5800);
DISPLAY 0.510638 (100 5800);
FORCEPROP 1 LAST VALUE 33.2
J 2
(0 5800);
DISPLAY 0.510638 (0 5800);
FORCEPROP 1 LAST PACK_TYPE 0402LF
J 0
(-325 5925);
DISPLAY 0.510638 (-325 5925);
FORCEPROP 1 LAST $LOCATION R579
J 0
(-475 5800);
DISPLAY 0.787234 (-475 5800);
FORCEPROP 1 LASTPIN (-300 5800) $PN 1
J 0
(-288 5812);
DISPLAY 0.787234 (-288 5812);
FORCEPROP 1 LASTPIN (-100 5800) $PN 2
J 0
(-138 5812);
DISPLAY 0.787234 (-138 5812);
FORCEPROP 2 LAST CDS_LIB pure_quanta
J 0
(-200 5800);
PAINT MONO (-200 5800);
DISPLAY INVISIBLE (-200 5800);
FORCEPROP 1 LAST PATH I38
J 0
(-250 5950);
DISPLAY 0.978723 (-250 5950);
PAINT WHITE (-250 5950);
DISPLAY INVISIBLE (-250 5950);
FORCEPROP 2 LAST CDS_LOCATION R579
J 0
(-250 6000);
DISPLAY 1.021277 (-250 6000);
DISPLAY INVISIBLE (-250 6000);
FORCEPROP 2 LAST $SEC 1
J 0
(-250 6000);
DISPLAY 0.680851 (-250 6000);
PAINT MONO (-250 6000);
DISPLAY INVISIBLE (-250 6000);
FORCEPROP 2 LAST CDS_SEC 1
J 0
(-250 6000);
DISPLAY 1.021277 (-250 6000);
DISPLAY INVISIBLE (-250 6000);
FORCEADD Q_RES..1
(-200 5750);
FORCEPROP 1 LAST PART_NUMBER CS03322FB03
J 0
(-325 5800);
DISPLAY 0.638298 (-325 5800);
DISPLAY INVISIBLE (-325 5800);
FORCEPROP 1 LAST MATERIAL CHIP
J 0
(100 5750);
DISPLAY 0.510638 (100 5750);
FORCEPROP 1 LAST VALUE 33.2
J 2
(0 5750);
DISPLAY 0.510638 (0 5750);
FORCEPROP 1 LAST TOLERANCE 1%
J 0
(25 5750);
DISPLAY 0.510638 (25 5750);
FORCEPROP 1 LAST $LOCATION R580
J 0
(-475 5750);
DISPLAY 0.787234 (-475 5750);
FORCEPROP 1 LASTPIN (-300 5750) $PN 1
J 0
(-288 5762);
DISPLAY 0.787234 (-288 5762);
FORCEPROP 1 LASTPIN (-100 5750) $PN 2
J 0
(-138 5762);
DISPLAY 0.787234 (-138 5762);
FORCEPROP 1 LAST PACK_TYPE 0402LF
J 0
(150 5750);
DISPLAY 0.638298 (150 5750);
DISPLAY INVISIBLE (150 5750);
FORCEPROP 1 LAST WATTAGE 1/16W
J 2
(0 5850);
DISPLAY 0.638298 (0 5850);
DISPLAY INVISIBLE (0 5850);
FORCEPROP 2 LAST CDS_LIB pure_quanta
J 0
(-200 5750);
PAINT MONO (-200 5750);
DISPLAY INVISIBLE (-200 5750);
FORCEPROP 1 LAST PATH I39
J 0
(-250 5900);
DISPLAY 0.978723 (-250 5900);
PAINT WHITE (-250 5900);
DISPLAY INVISIBLE (-250 5900);
FORCEPROP 2 LAST CDS_LOCATION R580
J 0
(-250 5950);
DISPLAY 1.021277 (-250 5950);
DISPLAY INVISIBLE (-250 5950);
FORCEPROP 2 LAST $SEC 1
J 0
(-250 5950);
DISPLAY 0.680851 (-250 5950);
PAINT MONO (-250 5950);
DISPLAY INVISIBLE (-250 5950);
FORCEPROP 2 LAST CDS_SEC 1
J 0
(-250 5950);
DISPLAY 1.021277 (-250 5950);
DISPLAY INVISIBLE (-250 5950);
FORCEADD Q_RES..1
(5000 5825);
FORCEPROP 1 LAST PART_NUMBER CS22002FB07
J 0
(4875 5900);
DISPLAY 0.638298 (4875 5900);
DISPLAY INVISIBLE (4875 5900);
FORCEPROP 1 LAST MATERIAL EMPTY
J 0
(5375 5825);
DISPLAY 0.638298 (5375 5825);
PAINT RED (5375 5825);
FORCEPROP 1 LAST VALUE 2K
J 2
(5225 5825);
DISPLAY 0.638298 (5225 5825);
FORCEPROP 1 LAST PACK_TYPE 0402LF
J 0
(4875 5950);
DISPLAY 0.638298 (4875 5950);
FORCEPROP 1 LAST WATTAGE 1/16W
J 2
(5250 5950);
DISPLAY 0.638298 (5250 5950);
FORCEPROP 1 LAST TOLERANCE 1%
J 0
(5275 5825);
DISPLAY 0.638298 (5275 5825);
FORCEPROP 1 LAST $LOCATION R1384
J 0
(4725 5825);
DISPLAY 0.638298 (4725 5825);
FORCEPROP 1 LASTPIN (4900 5825) $PN 1
J 0
(4912 5837);
DISPLAY 0.787234 (4912 5837);
FORCEPROP 1 LASTPIN (5100 5825) $PN 2
J 0
(5062 5837);
DISPLAY 0.787234 (5062 5837);
FORCEPROP 1 LAST PATH I4
J 0
(4950 5975);
DISPLAY 0.978723 (4950 5975);
PAINT WHITE (4950 5975);
DISPLAY INVISIBLE (4950 5975);
FORCEPROP 2 LAST CDS_LIB pure_quanta
J 0
(5000 5825);
PAINT MONO (5000 5825);
DISPLAY INVISIBLE (5000 5825);
FORCEPROP 2 LAST CDS_LOCATION R1384
J 0
(4950 6025);
DISPLAY 1.021277 (4950 6025);
DISPLAY INVISIBLE (4950 6025);
FORCEPROP 2 LAST $SEC 1
J 0
(4950 6025);
DISPLAY 0.680851 (4950 6025);
PAINT MONO (4950 6025);
DISPLAY INVISIBLE (4950 6025);
FORCEPROP 2 LAST CDS_SEC 1
J 0
(4950 6025);
DISPLAY 1.021277 (4950 6025);
DISPLAY INVISIBLE (4950 6025);
FORCEADD Q_RES..1
(-350 5500);
FORCEPROP 1 LAST PART_NUMBER CS00002JB13
J 0
(-400 5550);
DISPLAY 0.404255 (-400 5550);
DISPLAY INVISIBLE (-400 5550);
FORCEPROP 1 LAST TOLERANCE 5%
J 0
(-125 5500);
DISPLAY 0.510638 (-125 5500);
FORCEPROP 1 LAST MATERIAL CHIP
J 0
(-50 5450);
DISPLAY 0.510638 (-50 5450);
FORCEPROP 1 LAST VALUE 0
J 2
(-150 5500);
DISPLAY 0.510638 (-150 5500);
FORCEPROP 1 LAST $LOCATION R1525
J 0
(-625 5500);
DISPLAY 0.808511 (-625 5500);
FORCEPROP 1 LASTPIN (-450 5500) $PN 1
J 0
(-438 5512);
DISPLAY 0.787234 (-438 5512);
FORCEPROP 1 LASTPIN (-250 5500) $PN 2
J 0
(-288 5512);
DISPLAY 0.787234 (-288 5512);
FORCEPROP 2 LAST CDS_LIB pure_quanta
J 0
(-350 5500);
PAINT MONO (-350 5500);
DISPLAY INVISIBLE (-350 5500);
FORCEPROP 1 LAST PATH I40
J 0
(-400 5650);
DISPLAY 0.978723 (-400 5650);
PAINT WHITE (-400 5650);
DISPLAY INVISIBLE (-400 5650);
FORCEPROP 1 LAST WATTAGE 1/16W
J 2
(-175 5575);
DISPLAY 0.404255 (-175 5575);
DISPLAY INVISIBLE (-175 5575);
FORCEPROP 1 LAST PACK_TYPE 0402LF
J 0
(-100 5500);
DISPLAY 0.510638 (-100 5500);
DISPLAY INVISIBLE (-100 5500);
FORCEPROP 2 LAST CDS_LOCATION R1525
J 0
(-400 5700);
DISPLAY 1.021277 (-400 5700);
DISPLAY INVISIBLE (-400 5700);
FORCEPROP 2 LAST $SEC 1
J 0
(-400 5700);
DISPLAY 0.680851 (-400 5700);
PAINT MONO (-400 5700);
DISPLAY INVISIBLE (-400 5700);
FORCEPROP 2 LAST CDS_SEC 1
J 0
(-400 5700);
DISPLAY 1.021277 (-400 5700);
DISPLAY INVISIBLE (-400 5700);
FORCEADD Q_RES..1
(-350 5450);
FORCEPROP 1 LAST PART_NUMBER CS03322FB03
J 0
(-475 5575);
DISPLAY 0.510638 (-475 5575);
DISPLAY INVISIBLE (-475 5575);
FORCEPROP 1 LAST MATERIAL CHIP
J 0
(-50 5500);
DISPLAY 0.510638 (-50 5500);
FORCEPROP 1 LAST TOLERANCE 1%
J 0
(-125 5450);
DISPLAY 0.510638 (-125 5450);
FORCEPROP 1 LAST VALUE 33.2
J 2
(-150 5450);
DISPLAY 0.510638 (-150 5450);
FORCEPROP 1 LAST WATTAGE 1/16W
J 2
(-175 5625);
DISPLAY 0.510638 (-175 5625);
FORCEPROP 1 LAST PACK_TYPE 0402LF
J 0
(-475 5625);
DISPLAY 0.510638 (-475 5625);
FORCEPROP 1 LAST $LOCATION R1526
J 0
(-625 5450);
DISPLAY 0.808511 (-625 5450);
FORCEPROP 1 LASTPIN (-450 5450) $PN 1
J 0
(-438 5462);
DISPLAY 0.787234 (-438 5462);
FORCEPROP 1 LASTPIN (-250 5450) $PN 2
J 0
(-288 5462);
DISPLAY 0.787234 (-288 5462);
FORCEPROP 1 LAST PATH I41
J 0
(-400 5600);
DISPLAY 0.978723 (-400 5600);
PAINT WHITE (-400 5600);
DISPLAY INVISIBLE (-400 5600);
FORCEPROP 2 LAST CDS_LIB pure_quanta
J 0
(-350 5450);
PAINT MONO (-350 5450);
DISPLAY INVISIBLE (-350 5450);
FORCEPROP 2 LAST CDS_LOCATION R1526
J 0
(-400 5650);
DISPLAY 1.021277 (-400 5650);
DISPLAY INVISIBLE (-400 5650);
FORCEPROP 2 LAST $SEC 1
J 0
(-400 5650);
DISPLAY 0.680851 (-400 5650);
PAINT MONO (-400 5650);
DISPLAY INVISIBLE (-400 5650);
FORCEPROP 2 LAST CDS_SEC 1
J 0
(-400 5650);
DISPLAY 1.021277 (-400 5650);
DISPLAY INVISIBLE (-400 5650);
FORCEADD Q_RES..1
(-350 5125);
FORCEPROP 1 LAST PART_NUMBER CS03322FB03
J 0
(-475 5250);
DISPLAY 0.510638 (-475 5250);
DISPLAY INVISIBLE (-475 5250);
FORCEPROP 1 LAST MATERIAL CHIP
J 0
(-50 5125);
DISPLAY 0.510638 (-50 5125);
FORCEPROP 1 LAST TOLERANCE 1%
J 0
(-125 5125);
DISPLAY 0.510638 (-125 5125);
FORCEPROP 1 LAST VALUE 33.2
J 2
(-150 5125);
DISPLAY 0.510638 (-150 5125);
FORCEPROP 1 LAST PACK_TYPE 0402LF
J 0
(-475 5300);
DISPLAY 0.510638 (-475 5300);
FORCEPROP 1 LAST WATTAGE 1/16W
J 2
(-175 5300);
DISPLAY 0.510638 (-175 5300);
FORCEPROP 1 LAST $LOCATION R108
J 0
(-625 5125);
DISPLAY 0.808511 (-625 5125);
FORCEPROP 1 LASTPIN (-450 5125) $PN 1
J 0
(-438 5137);
DISPLAY 0.787234 (-438 5137);
FORCEPROP 1 LASTPIN (-250 5125) $PN 2
J 0
(-288 5137);
DISPLAY 0.787234 (-288 5137);
FORCEPROP 2 LAST CDS_LIB pure_quanta
J 0
(-350 5125);
PAINT MONO (-350 5125);
DISPLAY INVISIBLE (-350 5125);
FORCEPROP 1 LAST PATH I42
J 0
(-400 5275);
DISPLAY 0.978723 (-400 5275);
PAINT WHITE (-400 5275);
DISPLAY INVISIBLE (-400 5275);
FORCEPROP 2 LAST CDS_LOCATION R108
J 0
(-400 5325);
DISPLAY 1.021277 (-400 5325);
DISPLAY INVISIBLE (-400 5325);
FORCEPROP 2 LAST $SEC 1
J 0
(-400 5325);
DISPLAY 0.680851 (-400 5325);
PAINT MONO (-400 5325);
DISPLAY INVISIBLE (-400 5325);
FORCEPROP 2 LAST CDS_SEC 1
J 0
(-400 5325);
DISPLAY 1.021277 (-400 5325);
DISPLAY INVISIBLE (-400 5325);
FORCEADD Q_RES..1
(-350 5175);
FORCEPROP 1 LAST PART_NUMBER CS03322FB03
J 0
(-400 5225);
DISPLAY 0.404255 (-400 5225);
DISPLAY INVISIBLE (-400 5225);
FORCEPROP 1 LAST VALUE 33.2
J 2
(-150 5175);
DISPLAY 0.510638 (-150 5175);
FORCEPROP 1 LAST MATERIAL CHIP
J 0
(-50 5175);
DISPLAY 0.510638 (-50 5175);
FORCEPROP 1 LAST TOLERANCE 1%
J 0
(-125 5175);
DISPLAY 0.510638 (-125 5175);
FORCEPROP 1 LAST $LOCATION R107
J 0
(-625 5175);
DISPLAY 0.808511 (-625 5175);
FORCEPROP 1 LASTPIN (-450 5175) $PN 1
J 0
(-438 5187);
DISPLAY 0.787234 (-438 5187);
FORCEPROP 1 LASTPIN (-250 5175) $PN 2
J 0
(-288 5187);
DISPLAY 0.787234 (-288 5187);
FORCEPROP 2 LAST CDS_LIB pure_quanta
J 0
(-350 5175);
PAINT MONO (-350 5175);
DISPLAY INVISIBLE (-350 5175);
FORCEPROP 1 LAST WATTAGE 1/16W
J 2
(-175 5250);
DISPLAY 0.404255 (-175 5250);
DISPLAY INVISIBLE (-175 5250);
FORCEPROP 1 LAST PACK_TYPE 0402LF
J 0
(-100 5175);
DISPLAY 0.510638 (-100 5175);
DISPLAY INVISIBLE (-100 5175);
FORCEPROP 1 LAST PATH I43
J 0
(-400 5325);
DISPLAY 0.978723 (-400 5325);
PAINT WHITE (-400 5325);
DISPLAY INVISIBLE (-400 5325);
FORCEPROP 2 LAST CDS_LOCATION R107
J 0
(-400 5375);
DISPLAY 1.021277 (-400 5375);
DISPLAY INVISIBLE (-400 5375);
FORCEPROP 2 LAST $SEC 1
J 0
(-400 5375);
DISPLAY 0.680851 (-400 5375);
PAINT MONO (-400 5375);
DISPLAY INVISIBLE (-400 5375);
FORCEPROP 2 LAST CDS_SEC 1
J 0
(-400 5375);
DISPLAY 1.021277 (-400 5375);
DISPLAY INVISIBLE (-400 5375);
FORCEADD Q_RES..1
(-325 4550);
FORCEPROP 1 LAST PART_NUMBER CS03322FB03
J 0
(-450 4625);
DISPLAY 0.510638 (-450 4625);
DISPLAY INVISIBLE (-450 4625);
FORCEPROP 1 LAST VALUE 33.2
J 2
(-125 4550);
DISPLAY 0.510638 (-125 4550);
FORCEPROP 1 LAST TOLERANCE 1%
J 0
(-100 4550);
DISPLAY 0.510638 (-100 4550);
FORCEPROP 1 LAST WATTAGE 1/16W
J 2
(-125 4675);
DISPLAY 0.510638 (-125 4675);
FORCEPROP 1 LAST PACK_TYPE 0402LF
J 0
(-450 4675);
DISPLAY 0.510638 (-450 4675);
FORCEPROP 1 LAST MATERIAL CHIP
J 0
(-25 4550);
DISPLAY 0.510638 (-25 4550);
FORCEPROP 1 LAST $LOCATION R581
J 0
(-600 4550);
DISPLAY 0.787234 (-600 4550);
FORCEPROP 1 LASTPIN (-425 4550) $PN 1
J 0
(-413 4562);
DISPLAY 0.787234 (-413 4562);
FORCEPROP 1 LASTPIN (-225 4550) $PN 2
J 0
(-263 4562);
DISPLAY 0.787234 (-263 4562);
FORCEPROP 1 LAST PATH I44
J 0
(-375 4700);
DISPLAY 0.978723 (-375 4700);
PAINT WHITE (-375 4700);
DISPLAY INVISIBLE (-375 4700);
FORCEPROP 2 LAST CDS_LIB pure_quanta
J 0
(-325 4550);
PAINT MONO (-325 4550);
DISPLAY INVISIBLE (-325 4550);
FORCEPROP 2 LAST CDS_LOCATION R581
J 0
(-375 4750);
DISPLAY 1.021277 (-375 4750);
DISPLAY INVISIBLE (-375 4750);
FORCEPROP 2 LAST $SEC 1
J 0
(-375 4750);
DISPLAY 0.680851 (-375 4750);
PAINT MONO (-375 4750);
DISPLAY INVISIBLE (-375 4750);
FORCEPROP 2 LAST CDS_SEC 1
J 0
(-375 4750);
DISPLAY 1.021277 (-375 4750);
DISPLAY INVISIBLE (-375 4750);
FORCEADD Q_RES..1
(-325 4500);
FORCEPROP 1 LAST PART_NUMBER CS03322FB03
J 0
(-450 4550);
DISPLAY 0.638298 (-450 4550);
DISPLAY INVISIBLE (-450 4550);
FORCEPROP 1 LAST TOLERANCE 1%
J 0
(-100 4500);
DISPLAY 0.510638 (-100 4500);
FORCEPROP 1 LAST VALUE 33.2
J 2
(-125 4500);
DISPLAY 0.510638 (-125 4500);
FORCEPROP 1 LAST MATERIAL CHIP
J 0
(-25 4500);
DISPLAY 0.510638 (-25 4500);
FORCEPROP 1 LAST $LOCATION R582
J 0
(-600 4500);
DISPLAY 0.787234 (-600 4500);
FORCEPROP 1 LASTPIN (-425 4500) $PN 1
J 0
(-413 4512);
DISPLAY 0.787234 (-413 4512);
FORCEPROP 1 LASTPIN (-225 4500) $PN 2
J 0
(-263 4512);
DISPLAY 0.787234 (-263 4512);
FORCEPROP 1 LAST PATH I45
J 0
(-375 4650);
DISPLAY 0.978723 (-375 4650);
PAINT WHITE (-375 4650);
DISPLAY INVISIBLE (-375 4650);
FORCEPROP 1 LAST PACK_TYPE 0402LF
J 0
(25 4500);
DISPLAY 0.638298 (25 4500);
DISPLAY INVISIBLE (25 4500);
FORCEPROP 1 LAST WATTAGE 1/16W
J 2
(-125 4600);
DISPLAY 0.638298 (-125 4600);
DISPLAY INVISIBLE (-125 4600);
FORCEPROP 2 LAST CDS_LIB pure_quanta
J 0
(-325 4500);
PAINT MONO (-325 4500);
DISPLAY INVISIBLE (-325 4500);
FORCEPROP 2 LAST CDS_LOCATION R582
J 0
(-375 4700);
DISPLAY 1.021277 (-375 4700);
DISPLAY INVISIBLE (-375 4700);
FORCEPROP 2 LAST $SEC 1
J 0
(-375 4700);
DISPLAY 0.680851 (-375 4700);
PAINT MONO (-375 4700);
DISPLAY INVISIBLE (-375 4700);
FORCEPROP 2 LAST CDS_SEC 1
J 0
(-375 4700);
DISPLAY 1.021277 (-375 4700);
DISPLAY INVISIBLE (-375 4700);
FORCEADD Q_RES..1
(5000 5775);
FORCEPROP 1 LAST PART_NUMBER CS22002FB07
J 0
(4875 5825);
DISPLAY 0.638298 (4875 5825);
DISPLAY INVISIBLE (4875 5825);
FORCEPROP 1 LAST MATERIAL EMPTY
J 0
(5375 5775);
DISPLAY 0.638298 (5375 5775);
PAINT RED (5375 5775);
FORCEPROP 1 LAST TOLERANCE 1%
J 0
(5275 5775);
DISPLAY 0.638298 (5275 5775);
FORCEPROP 1 LAST VALUE 2K
J 2
(5225 5775);
DISPLAY 0.638298 (5225 5775);
FORCEPROP 1 LAST $LOCATION R1385
J 0
(4725 5775);
DISPLAY 0.638298 (4725 5775);
FORCEPROP 1 LASTPIN (4900 5775) $PN 1
J 0
(4912 5787);
DISPLAY 0.787234 (4912 5787);
FORCEPROP 1 LASTPIN (5100 5775) $PN 2
J 0
(5062 5787);
DISPLAY 0.787234 (5062 5787);
FORCEPROP 1 LAST PATH I5
J 0
(4950 5925);
DISPLAY 0.978723 (4950 5925);
PAINT WHITE (4950 5925);
DISPLAY INVISIBLE (4950 5925);
FORCEPROP 1 LAST PACK_TYPE 0402LF
J 0
(4875 5875);
DISPLAY 0.638298 (4875 5875);
DISPLAY INVISIBLE (4875 5875);
FORCEPROP 1 LAST WATTAGE 1/16W
J 2
(5300 5875);
DISPLAY 0.638298 (5300 5875);
DISPLAY INVISIBLE (5300 5875);
FORCEPROP 2 LAST CDS_LIB pure_quanta
J 0
(5000 5775);
PAINT MONO (5000 5775);
DISPLAY INVISIBLE (5000 5775);
FORCEPROP 2 LAST CDS_LOCATION R1385
J 0
(4950 5975);
DISPLAY 1.021277 (4950 5975);
DISPLAY INVISIBLE (4950 5975);
FORCEPROP 2 LAST $SEC 1
J 0
(4950 5975);
DISPLAY 0.680851 (4950 5975);
PAINT MONO (4950 5975);
DISPLAY INVISIBLE (4950 5975);
FORCEPROP 2 LAST CDS_SEC 1
J 0
(4950 5975);
DISPLAY 1.021277 (4950 5975);
DISPLAY INVISIBLE (4950 5975);
FORCEADD OFFPAGE..1
(-2250 5500);
FORCEPROP 2 LAST $XR0 241 
J 0
(-2502 5500);
DISPLAY 0.638298 (-2502 5500);
PAINT MONO (-2502 5500);
FORCEPROP 2 LAST CDS_LIB standard
J 0
(-2250 5500);
PAINT MONO (-2250 5500);
DISPLAY INVISIBLE (-2250 5500);
FORCEPROP 2 LAST PATH I52
J 0
(-2525 5550);
DISPLAY 1.021277 (-2525 5550);
DISPLAY INVISIBLE (-2525 5550);
FORCEPROP 1 LAST COMMENT_BODY TRUE
J 0
(-2125 5400);
DISPLAY 0.872340 (-2125 5400);
PAINT GREEN (-2125 5400);
DISPLAY INVISIBLE (-2125 5400);
FORCEPROP 1 LAST OFFPAGE TRUE
J 0
(-1925 5375);
DISPLAY 0.872340 (-1925 5375);
PAINT GREEN (-1925 5375);
DISPLAY INVISIBLE (-1925 5375);
FORCEADD OFFPAGE..3
R 2
(-2250 5450);
FORCEPROP 2 LAST $XR0 241 
J 0
(-2530 5450);
DISPLAY 0.638298 (-2530 5450);
PAINT MONO (-2530 5450);
FORCEPROP 2 LAST CDS_LIB standard
J 0
(-2250 5450);
PAINT MONO (-2250 5450);
DISPLAY INVISIBLE (-2250 5450);
FORCEPROP 2 LAST PATH I53
J 0
(-2575 5500);
DISPLAY 1.021277 (-2575 5500);
DISPLAY INVISIBLE (-2575 5500);
FORCEPROP 1 LAST OFFPAGE TRUE
J 2
(-2575 5325);
DISPLAY 0.872340 (-2575 5325);
DISPLAY INVISIBLE (-2575 5325);
FORCEPROP 1 LAST COMMENT_BODY TRUE
J 2
(-2200 5350);
DISPLAY 0.872340 (-2200 5350);
PAINT GREEN (-2200 5350);
DISPLAY INVISIBLE (-2200 5350);
FORCEADD OFFPAGE..1
(-2050 4550);
FORCEPROP 2 LAST $XR1 241 
J 0
(-2422 4550);
DISPLAY 0.638298 (-2422 4550);
PAINT MONO (-2422 4550);
FORCEPROP 2 LAST $XR0 240 
J 0
(-2302 4550);
DISPLAY 0.638298 (-2302 4550);
PAINT MONO (-2302 4550);
FORCEPROP 2 LAST PATH I54
J 0
(-2325 4600);
DISPLAY 1.021277 (-2325 4600);
DISPLAY INVISIBLE (-2325 4600);
FORCEPROP 2 LAST CDS_LIB standard
J 0
(-2050 4550);
PAINT MONO (-2050 4550);
DISPLAY INVISIBLE (-2050 4550);
FORCEPROP 1 LAST COMMENT_BODY TRUE
J 0
(-1925 4450);
DISPLAY 0.872340 (-1925 4450);
PAINT GREEN (-1925 4450);
DISPLAY INVISIBLE (-1925 4450);
FORCEPROP 1 LAST OFFPAGE TRUE
J 0
(-1725 4425);
DISPLAY 0.872340 (-1725 4425);
PAINT GREEN (-1725 4425);
DISPLAY INVISIBLE (-1725 4425);
FORCEADD OFFPAGE..3
R 2
(-2050 4500);
FORCEPROP 2 LAST $XR1 241 
J 0
(-2450 4500);
DISPLAY 0.638298 (-2450 4500);
PAINT MONO (-2450 4500);
FORCEPROP 2 LAST $XR0 240 
J 0
(-2330 4500);
DISPLAY 0.638298 (-2330 4500);
PAINT MONO (-2330 4500);
FORCEPROP 2 LAST PATH I55
J 0
(-2375 4550);
DISPLAY 1.021277 (-2375 4550);
DISPLAY INVISIBLE (-2375 4550);
FORCEPROP 1 LAST OFFPAGE TRUE
J 2
(-2375 4375);
DISPLAY 0.872340 (-2375 4375);
DISPLAY INVISIBLE (-2375 4375);
FORCEPROP 1 LAST COMMENT_BODY TRUE
J 2
(-2000 4400);
DISPLAY 0.872340 (-2000 4400);
PAINT GREEN (-2000 4400);
DISPLAY INVISIBLE (-2000 4400);
FORCEPROP 2 LAST CDS_LIB standard
J 0
(-2050 4500);
PAINT MONO (-2050 4500);
DISPLAY INVISIBLE (-2050 4500);
FORCEADD OFFPAGE..1
(-2050 3925);
FORCEPROP 2 LAST $XR2 183 
J 0
(-2542 3925);
DISPLAY 0.638298 (-2542 3925);
PAINT MONO (-2542 3925);
FORCEPROP 2 LAST $XR1 241 
J 0
(-2422 3925);
DISPLAY 0.638298 (-2422 3925);
PAINT MONO (-2422 3925);
FORCEPROP 2 LAST $XR0 240 
J 0
(-2302 3925);
DISPLAY 0.638298 (-2302 3925);
PAINT MONO (-2302 3925);
FORCEPROP 2 LAST PATH I56
J 0
(-2325 3975);
DISPLAY 1.021277 (-2325 3975);
DISPLAY INVISIBLE (-2325 3975);
FORCEPROP 1 LAST COMMENT_BODY TRUE
J 0
(-1925 3825);
DISPLAY 0.872340 (-1925 3825);
PAINT GREEN (-1925 3825);
DISPLAY INVISIBLE (-1925 3825);
FORCEPROP 1 LAST OFFPAGE TRUE
J 0
(-1725 3800);
DISPLAY 0.872340 (-1725 3800);
PAINT GREEN (-1725 3800);
DISPLAY INVISIBLE (-1725 3800);
FORCEPROP 2 LAST CDS_LIB standard
J 0
(-2050 3925);
PAINT MONO (-2050 3925);
DISPLAY INVISIBLE (-2050 3925);
FORCEADD OFFPAGE..3
R 2
(-2050 3875);
FORCEPROP 2 LAST $XR2 241 
J 0
(-2570 3875);
DISPLAY 0.638298 (-2570 3875);
PAINT MONO (-2570 3875);
FORCEPROP 2 LAST $XR1 240 
J 0
(-2450 3875);
DISPLAY 0.638298 (-2450 3875);
PAINT MONO (-2450 3875);
FORCEPROP 2 LAST $XR0 183 
J 0
(-2330 3875);
DISPLAY 0.638298 (-2330 3875);
PAINT MONO (-2330 3875);
FORCEPROP 2 LAST PATH I57
J 0
(-2375 3925);
DISPLAY 1.021277 (-2375 3925);
DISPLAY INVISIBLE (-2375 3925);
FORCEPROP 1 LAST OFFPAGE TRUE
J 2
(-2375 3750);
DISPLAY 0.872340 (-2375 3750);
DISPLAY INVISIBLE (-2375 3750);
FORCEPROP 1 LAST COMMENT_BODY TRUE
J 2
(-2000 3775);
DISPLAY 0.872340 (-2000 3775);
PAINT GREEN (-2000 3775);
DISPLAY INVISIBLE (-2000 3775);
FORCEPROP 2 LAST CDS_LIB standard
J 0
(-2050 3875);
PAINT MONO (-2050 3875);
DISPLAY INVISIBLE (-2050 3875);
FORCEADD Q_RES..1
(5000 5575);
FORCEPROP 1 LAST PART_NUMBER CS22002FB07
J 0
(4875 5650);
DISPLAY 0.638298 (4875 5650);
DISPLAY INVISIBLE (4875 5650);
FORCEPROP 1 LAST TOLERANCE 1%
J 0
(5275 5575);
DISPLAY 0.638298 (5275 5575);
FORCEPROP 1 LAST MATERIAL EMPTY
J 0
(5375 5575);
DISPLAY 0.638298 (5375 5575);
PAINT RED (5375 5575);
FORCEPROP 1 LAST PACK_TYPE 0402LF
J 0
(4875 5700);
DISPLAY 0.638298 (4875 5700);
FORCEPROP 1 LAST WATTAGE 1/16W
J 2
(5250 5700);
DISPLAY 0.638298 (5250 5700);
FORCEPROP 1 LAST VALUE 2K
J 2
(5225 5575);
DISPLAY 0.638298 (5225 5575);
FORCEPROP 1 LAST $LOCATION R1386
J 0
(4725 5575);
DISPLAY 0.638298 (4725 5575);
FORCEPROP 1 LASTPIN (4900 5575) $PN 1
J 0
(4912 5587);
DISPLAY 0.787234 (4912 5587);
FORCEPROP 1 LASTPIN (5100 5575) $PN 2
J 0
(5062 5587);
DISPLAY 0.787234 (5062 5587);
FORCEPROP 1 LAST PATH I6
J 0
(4950 5725);
DISPLAY 0.978723 (4950 5725);
PAINT WHITE (4950 5725);
DISPLAY INVISIBLE (4950 5725);
FORCEPROP 2 LAST CDS_LIB pure_quanta
J 0
(5000 5575);
PAINT MONO (5000 5575);
DISPLAY INVISIBLE (5000 5575);
FORCEPROP 2 LAST CDS_LOCATION R1386
J 0
(4950 5775);
DISPLAY 1.021277 (4950 5775);
DISPLAY INVISIBLE (4950 5775);
FORCEPROP 2 LAST $SEC 1
J 0
(4950 5775);
DISPLAY 0.680851 (4950 5775);
PAINT MONO (4950 5775);
DISPLAY INVISIBLE (4950 5775);
FORCEPROP 2 LAST CDS_SEC 1
J 0
(4950 5775);
DISPLAY 1.021277 (4950 5775);
DISPLAY INVISIBLE (4950 5775);
FORCEADD OFFPAGE..1
(2350 2050);
FORCEPROP 2 LAST $XR0 240 
J 0
(2098 2050);
DISPLAY 0.638298 (2098 2050);
PAINT MONO (2098 2050);
FORCEPROP 2 LAST CDS_LIB standard
J 0
(2350 2050);
PAINT MONO (2350 2050);
DISPLAY INVISIBLE (2350 2050);
FORCEPROP 1 LAST COMMENT_BODY TRUE
J 0
(2475 1950);
DISPLAY 0.872340 (2475 1950);
PAINT GREEN (2475 1950);
DISPLAY INVISIBLE (2475 1950);
FORCEPROP 1 LAST OFFPAGE TRUE
J 0
(2675 1925);
DISPLAY 0.872340 (2675 1925);
PAINT GREEN (2675 1925);
DISPLAY INVISIBLE (2675 1925);
FORCEPROP 2 LAST PATH I66
J 0
(2075 2100);
DISPLAY 1.021277 (2075 2100);
DISPLAY INVISIBLE (2075 2100);
FORCEADD OFFPAGE..3
R 2
(2350 2000);
FORCEPROP 2 LAST $XR0 240 
J 0
(2070 2000);
DISPLAY 0.638298 (2070 2000);
PAINT MONO (2070 2000);
FORCEPROP 1 LAST OFFPAGE TRUE
J 2
(2025 1875);
DISPLAY 0.872340 (2025 1875);
DISPLAY INVISIBLE (2025 1875);
FORCEPROP 1 LAST COMMENT_BODY TRUE
J 2
(2400 1900);
DISPLAY 0.872340 (2400 1900);
PAINT GREEN (2400 1900);
DISPLAY INVISIBLE (2400 1900);
FORCEPROP 2 LAST CDS_LIB standard
J 0
(2350 2000);
PAINT MONO (2350 2000);
DISPLAY INVISIBLE (2350 2000);
FORCEPROP 2 LAST PATH I67
J 0
(2025 2050);
DISPLAY 1.021277 (2025 2050);
DISPLAY INVISIBLE (2025 2050);
FORCEADD OFFPAGE..1
(2350 1750);
FORCEPROP 2 LAST $XR0 240 
J 0
(2098 1750);
DISPLAY 0.638298 (2098 1750);
PAINT MONO (2098 1750);
FORCEPROP 1 LAST OFFPAGE TRUE
J 0
(2675 1625);
DISPLAY 0.872340 (2675 1625);
PAINT GREEN (2675 1625);
DISPLAY INVISIBLE (2675 1625);
FORCEPROP 1 LAST COMMENT_BODY TRUE
J 0
(2475 1650);
DISPLAY 0.872340 (2475 1650);
PAINT GREEN (2475 1650);
DISPLAY INVISIBLE (2475 1650);
FORCEPROP 2 LAST CDS_LIB standard
J 0
(2350 1750);
PAINT MONO (2350 1750);
DISPLAY INVISIBLE (2350 1750);
FORCEPROP 2 LAST PATH I68
J 0
(2075 1800);
DISPLAY 1.021277 (2075 1800);
DISPLAY INVISIBLE (2075 1800);
FORCEADD OFFPAGE..3
R 2
(2350 1700);
FORCEPROP 2 LAST $XR0 240 
J 0
(2070 1700);
DISPLAY 0.638298 (2070 1700);
PAINT MONO (2070 1700);
FORCEPROP 2 LAST CDS_LIB standard
J 0
(2350 1700);
PAINT MONO (2350 1700);
DISPLAY INVISIBLE (2350 1700);
FORCEPROP 1 LAST COMMENT_BODY TRUE
J 2
(2400 1600);
DISPLAY 0.872340 (2400 1600);
PAINT GREEN (2400 1600);
DISPLAY INVISIBLE (2400 1600);
FORCEPROP 1 LAST OFFPAGE TRUE
J 2
(2025 1575);
DISPLAY 0.872340 (2025 1575);
DISPLAY INVISIBLE (2025 1575);
FORCEPROP 2 LAST PATH I69
J 0
(2025 1750);
DISPLAY 1.021277 (2025 1750);
DISPLAY INVISIBLE (2025 1750);
FORCEADD Q_RES..1
(5000 5525);
FORCEPROP 1 LAST PART_NUMBER CS22002FB07
J 0
(4875 5575);
DISPLAY 0.638298 (4875 5575);
DISPLAY INVISIBLE (4875 5575);
FORCEPROP 1 LAST VALUE 2K
J 2
(5225 5525);
DISPLAY 0.638298 (5225 5525);
FORCEPROP 1 LAST MATERIAL EMPTY
J 0
(5375 5525);
DISPLAY 0.638298 (5375 5525);
PAINT RED (5375 5525);
FORCEPROP 1 LAST TOLERANCE 1%
J 0
(5275 5525);
DISPLAY 0.638298 (5275 5525);
FORCEPROP 1 LAST $LOCATION R1387
J 0
(4725 5525);
DISPLAY 0.638298 (4725 5525);
FORCEPROP 1 LASTPIN (4900 5525) $PN 1
J 0
(4912 5537);
DISPLAY 0.787234 (4912 5537);
FORCEPROP 1 LASTPIN (5100 5525) $PN 2
J 0
(5062 5537);
DISPLAY 0.787234 (5062 5537);
FORCEPROP 1 LAST PATH I7
J 0
(4950 5675);
DISPLAY 0.978723 (4950 5675);
PAINT WHITE (4950 5675);
DISPLAY INVISIBLE (4950 5675);
FORCEPROP 2 LAST CDS_LIB pure_quanta
J 0
(5000 5525);
PAINT MONO (5000 5525);
DISPLAY INVISIBLE (5000 5525);
FORCEPROP 1 LAST WATTAGE 1/16W
J 2
(5300 5625);
DISPLAY 0.638298 (5300 5625);
DISPLAY INVISIBLE (5300 5625);
FORCEPROP 1 LAST PACK_TYPE 0402LF
J 0
(4875 5625);
DISPLAY 0.638298 (4875 5625);
DISPLAY INVISIBLE (4875 5625);
FORCEPROP 2 LAST CDS_LOCATION R1387
J 0
(4950 5725);
DISPLAY 1.021277 (4950 5725);
DISPLAY INVISIBLE (4950 5725);
FORCEPROP 2 LAST $SEC 1
J 0
(4950 5725);
DISPLAY 0.680851 (4950 5725);
PAINT MONO (4950 5725);
DISPLAY INVISIBLE (4950 5725);
FORCEPROP 2 LAST CDS_SEC 1
J 0
(4950 5725);
DISPLAY 1.021277 (4950 5725);
DISPLAY INVISIBLE (4950 5725);
FORCEADD OFFPAGE..1
(2350 1425);
FORCEPROP 2 LAST $XR0 240 
J 0
(2098 1425);
DISPLAY 0.638298 (2098 1425);
PAINT MONO (2098 1425);
FORCEPROP 1 LAST OFFPAGE TRUE
J 0
(2675 1300);
DISPLAY 0.872340 (2675 1300);
PAINT GREEN (2675 1300);
DISPLAY INVISIBLE (2675 1300);
FORCEPROP 1 LAST COMMENT_BODY TRUE
J 0
(2475 1325);
DISPLAY 0.872340 (2475 1325);
PAINT GREEN (2475 1325);
DISPLAY INVISIBLE (2475 1325);
FORCEPROP 2 LAST CDS_LIB standard
J 0
(2350 1425);
PAINT MONO (2350 1425);
DISPLAY INVISIBLE (2350 1425);
FORCEPROP 2 LAST PATH I70
J 0
(2075 1475);
DISPLAY 1.021277 (2075 1475);
DISPLAY INVISIBLE (2075 1475);
FORCEADD OFFPAGE..3
R 2
(2350 1375);
FORCEPROP 2 LAST $XR0 240 
J 0
(2070 1375);
DISPLAY 0.638298 (2070 1375);
PAINT MONO (2070 1375);
FORCEPROP 2 LAST CDS_LIB standard
J 0
(2350 1375);
PAINT MONO (2350 1375);
DISPLAY INVISIBLE (2350 1375);
FORCEPROP 1 LAST COMMENT_BODY TRUE
J 2
(2400 1275);
DISPLAY 0.872340 (2400 1275);
PAINT GREEN (2400 1275);
DISPLAY INVISIBLE (2400 1275);
FORCEPROP 1 LAST OFFPAGE TRUE
J 2
(2025 1250);
DISPLAY 0.872340 (2025 1250);
DISPLAY INVISIBLE (2025 1250);
FORCEPROP 2 LAST PATH I71
J 0
(2025 1425);
DISPLAY 1.021277 (2025 1425);
DISPLAY INVISIBLE (2025 1425);
FORCEADD OFFPAGE..1
(2350 1125);
FORCEPROP 2 LAST $XR0 240 
J 0
(2098 1125);
DISPLAY 0.638298 (2098 1125);
PAINT MONO (2098 1125);
FORCEPROP 1 LAST OFFPAGE TRUE
J 0
(2675 1000);
DISPLAY 0.872340 (2675 1000);
PAINT GREEN (2675 1000);
DISPLAY INVISIBLE (2675 1000);
FORCEPROP 1 LAST COMMENT_BODY TRUE
J 0
(2475 1025);
DISPLAY 0.872340 (2475 1025);
PAINT GREEN (2475 1025);
DISPLAY INVISIBLE (2475 1025);
FORCEPROP 2 LAST CDS_LIB standard
J 0
(2350 1125);
PAINT MONO (2350 1125);
DISPLAY INVISIBLE (2350 1125);
FORCEPROP 2 LAST PATH I72
J 0
(2075 1175);
DISPLAY 1.021277 (2075 1175);
DISPLAY INVISIBLE (2075 1175);
FORCEADD OFFPAGE..3
R 2
(2350 1075);
FORCEPROP 2 LAST $XR0 240 
J 0
(2070 1075);
DISPLAY 0.638298 (2070 1075);
PAINT MONO (2070 1075);
FORCEPROP 2 LAST CDS_LIB standard
J 0
(2350 1075);
PAINT MONO (2350 1075);
DISPLAY INVISIBLE (2350 1075);
FORCEPROP 1 LAST COMMENT_BODY TRUE
J 2
(2400 975);
DISPLAY 0.872340 (2400 975);
PAINT GREEN (2400 975);
DISPLAY INVISIBLE (2400 975);
FORCEPROP 1 LAST OFFPAGE TRUE
J 2
(2025 950);
DISPLAY 0.872340 (2025 950);
DISPLAY INVISIBLE (2025 950);
FORCEPROP 2 LAST PATH I73
J 0
(2025 1125);
DISPLAY 1.021277 (2025 1125);
DISPLAY INVISIBLE (2025 1125);
FORCEADD OFFPAGE..5
(3500 6075);
FORCEPROP 2 LAST $XR1 241 
J 0
(3095 6075);
DISPLAY 0.638298 (3095 6075);
PAINT MONO (3095 6075);
FORCEPROP 2 LAST $XR0 240 
J 0
(3215 6075);
DISPLAY 0.638298 (3215 6075);
PAINT MONO (3215 6075);
FORCEPROP 1 LAST COMMENT_BODY TRUE
J 0
(3600 6000);
DISPLAY 0.872340 (3600 6000);
PAINT PEACH (3600 6000);
DISPLAY INVISIBLE (3600 6000);
FORCEPROP 1 LAST OFFPAGE TRUE
J 0
(3825 5950);
DISPLAY 0.872340 (3825 5950);
PAINT GREEN (3825 5950);
DISPLAY INVISIBLE (3825 5950);
FORCEPROP 2 LAST CDS_LIB standard
J 0
(3500 6075);
PAINT MONO (3500 6075);
DISPLAY INVISIBLE (3500 6075);
FORCEPROP 2 LAST PATH I8
J 0
(3225 6125);
DISPLAY 1.021277 (3225 6125);
DISPLAY INVISIBLE (3225 6125);
FORCEADD Q_RES..1
(-325 2725);
FORCEPROP 1 LAST PART_NUMBER CS03322FB03
J 0
(-450 2800);
DISPLAY 0.510638 (-450 2800);
DISPLAY INVISIBLE (-450 2800);
FORCEPROP 1 LAST WATTAGE 1/16W
J 2
(-150 2850);
DISPLAY 0.510638 (-150 2850);
FORCEPROP 1 LAST TOLERANCE 1%
J 0
(-100 2725);
DISPLAY 0.510638 (-100 2725);
FORCEPROP 1 LAST VALUE 33.2
J 2
(-125 2725);
DISPLAY 0.510638 (-125 2725);
FORCEPROP 1 LAST MATERIAL CHIP
J 0
(-25 2725);
DISPLAY 0.510638 (-25 2725);
FORCEPROP 1 LAST PACK_TYPE 0402LF
J 0
(-450 2850);
DISPLAY 0.510638 (-450 2850);
FORCEPROP 1 LAST $LOCATION R1661
J 0
(-575 2725);
DISPLAY 0.787234 (-575 2725);
FORCEPROP 1 LASTPIN (-425 2725) $PN 1
J 0
(-413 2737);
DISPLAY 0.787234 (-413 2737);
FORCEPROP 1 LASTPIN (-225 2725) $PN 2
J 0
(-263 2737);
DISPLAY 0.787234 (-263 2737);
FORCEPROP 2 LAST CDS_LIB pure_quanta
J 0
(-325 2725);
PAINT MONO (-325 2725);
DISPLAY INVISIBLE (-325 2725);
FORCEPROP 1 LAST PATH I89
J 0
(-375 2875);
DISPLAY 0.978723 (-375 2875);
PAINT WHITE (-375 2875);
DISPLAY INVISIBLE (-375 2875);
FORCEPROP 2 LAST CDS_LOCATION R1661
J 0
(-375 2925);
DISPLAY 1.021277 (-375 2925);
DISPLAY INVISIBLE (-375 2925);
FORCEPROP 2 LAST $SEC 1
J 0
(-375 2925);
DISPLAY 0.680851 (-375 2925);
PAINT MONO (-375 2925);
DISPLAY INVISIBLE (-375 2925);
FORCEPROP 2 LAST CDS_SEC 1
J 0
(-375 2925);
DISPLAY 1.021277 (-375 2925);
DISPLAY INVISIBLE (-375 2925);
FORCEADD OFFPAGE..5
(3500 6025);
FORCEPROP 2 LAST $XR1 241 
J 0
(3095 6025);
DISPLAY 0.638298 (3095 6025);
PAINT MONO (3095 6025);
FORCEPROP 2 LAST $XR0 240 
J 0
(3215 6025);
DISPLAY 0.638298 (3215 6025);
PAINT MONO (3215 6025);
FORCEPROP 1 LAST COMMENT_BODY TRUE
J 0
(3600 5950);
DISPLAY 0.872340 (3600 5950);
PAINT PEACH (3600 5950);
DISPLAY INVISIBLE (3600 5950);
FORCEPROP 1 LAST OFFPAGE TRUE
J 0
(3825 5900);
DISPLAY 0.872340 (3825 5900);
PAINT GREEN (3825 5900);
DISPLAY INVISIBLE (3825 5900);
FORCEPROP 2 LAST CDS_LIB standard
J 0
(3500 6025);
PAINT MONO (3500 6025);
DISPLAY INVISIBLE (3500 6025);
FORCEPROP 2 LAST PATH I9
J 0
(3200 6075);
DISPLAY 1.021277 (3200 6075);
DISPLAY INVISIBLE (3200 6075);
FORCEADD Q_RES..1
(-325 2675);
FORCEPROP 1 LAST PART_NUMBER CS03322FB03
J 0
(-450 2725);
DISPLAY 0.638298 (-450 2725);
DISPLAY INVISIBLE (-450 2725);
FORCEPROP 1 LAST MATERIAL CHIP
J 0
(-25 2675);
DISPLAY 0.510638 (-25 2675);
FORCEPROP 1 LAST VALUE 33.2
J 2
(-125 2675);
DISPLAY 0.510638 (-125 2675);
FORCEPROP 1 LAST TOLERANCE 1%
J 0
(-100 2675);
DISPLAY 0.510638 (-100 2675);
FORCEPROP 1 LAST $LOCATION R1662
J 0
(-575 2675);
DISPLAY 0.787234 (-575 2675);
FORCEPROP 1 LASTPIN (-425 2675) $PN 1
J 0
(-413 2687);
DISPLAY 0.787234 (-413 2687);
FORCEPROP 1 LASTPIN (-225 2675) $PN 2
J 0
(-263 2687);
DISPLAY 0.787234 (-263 2687);
FORCEPROP 2 LAST CDS_LIB pure_quanta
J 0
(-325 2675);
PAINT MONO (-325 2675);
DISPLAY INVISIBLE (-325 2675);
FORCEPROP 1 LAST PATH I90
J 0
(-375 2825);
DISPLAY 0.978723 (-375 2825);
PAINT WHITE (-375 2825);
DISPLAY INVISIBLE (-375 2825);
FORCEPROP 1 LAST PACK_TYPE 0402LF
J 0
(25 2675);
DISPLAY 0.638298 (25 2675);
DISPLAY INVISIBLE (25 2675);
FORCEPROP 1 LAST WATTAGE 1/16W
J 2
(-125 2775);
DISPLAY 0.638298 (-125 2775);
DISPLAY INVISIBLE (-125 2775);
FORCEPROP 2 LAST CDS_LOCATION R1662
J 0
(-375 2875);
DISPLAY 1.021277 (-375 2875);
DISPLAY INVISIBLE (-375 2875);
FORCEPROP 2 LAST $SEC 1
J 0
(-375 2875);
DISPLAY 0.680851 (-375 2875);
PAINT MONO (-375 2875);
DISPLAY INVISIBLE (-375 2875);
FORCEPROP 2 LAST CDS_SEC 1
J 0
(-375 2875);
DISPLAY 1.021277 (-375 2875);
DISPLAY INVISIBLE (-375 2875);
FORCEADD OFFPAGE..2
(1350 2725);
FORCEPROP 2 LAST $XR2 296 
J 0
(1779 2725);
DISPLAY 0.638298 (1779 2725);
PAINT MONO (1779 2725);
FORCEPROP 2 LAST $XR1 292 
J 0
(1659 2725);
DISPLAY 0.638298 (1659 2725);
PAINT MONO (1659 2725);
FORCEPROP 2 LAST $XR0 241 
J 0
(1539 2725);
DISPLAY 0.638298 (1539 2725);
PAINT MONO (1539 2725);
FORCEPROP 2 LAST PATH I91
J 0
(1550 2775);
DISPLAY 1.021277 (1550 2775);
DISPLAY INVISIBLE (1550 2775);
FORCEPROP 1 LAST COMMENT_BODY TRUE
J 0
(1305 2630);
DISPLAY 1.170213 (1305 2630);
PAINT GREEN (1305 2630);
DISPLAY INVISIBLE (1305 2630);
FORCEPROP 1 LAST OFFPAGE TRUE
J 0
(1675 2600);
DISPLAY 1.170213 (1675 2600);
PAINT GREEN (1675 2600);
DISPLAY INVISIBLE (1675 2600);
FORCEPROP 2 LAST CDS_LIB standard
J 0
(1350 2725);
PAINT MONO (1350 2725);
DISPLAY INVISIBLE (1350 2725);
FORCEADD OFFPAGE..3
(1350 2675);
FORCEPROP 2 LAST $XR2 296 
J 0
(1804 2675);
DISPLAY 0.638298 (1804 2675);
PAINT MONO (1804 2675);
FORCEPROP 2 LAST $XR1 292 
J 0
(1684 2675);
DISPLAY 0.638298 (1684 2675);
PAINT MONO (1684 2675);
FORCEPROP 2 LAST $XR0 241 
J 0
(1564 2675);
DISPLAY 0.638298 (1564 2675);
PAINT MONO (1564 2675);
FORCEPROP 2 LAST PATH I92
J 0
(1750 2725);
DISPLAY 1.021277 (1750 2725);
DISPLAY INVISIBLE (1750 2725);
FORCEPROP 2 LAST CDS_LIB standard
J 0
(1350 2675);
PAINT MONO (1350 2675);
DISPLAY INVISIBLE (1350 2675);
FORCEPROP 1 LAST COMMENT_BODY TRUE
J 0
(1300 2575);
DISPLAY 0.872340 (1300 2575);
PAINT GREEN (1300 2575);
DISPLAY INVISIBLE (1300 2575);
FORCEPROP 1 LAST OFFPAGE TRUE
J 0
(1675 2550);
DISPLAY 0.872340 (1675 2550);
DISPLAY INVISIBLE (1675 2550);
FORCEADD QUANTA_TITLE_BLOCK_C..1
(6175 325);
FORCEPROP 0 LAST CDS_CON_LAST_MODIFIED Fri Aug 25 14:04:08 2023
J 0
(4290 340);
PAINT MONO (4290 340);
DISPLAY INVISIBLE (4290 340);
FORCEPROP 2 LAST CUSTOM_TXT_CDS <XR_PAGE_TITLE>
J 0
(-1715 5575);
DISPLAY 0.638298 (-1715 5575);
PAINT PINK (-1715 5575);
DISPLAY INVISIBLE (-1715 5575);
FORCEPROP 2 LAST CUSTOM_TXT_CDS <CON_LAST_MODIFIED>
J 0
(4290 340);
DISPLAY 0.978723 (4290 340);
FORCEPROP 2 LAST CUSTOM_TXT_CDS <Q_REV>
J 0
(5991 428);
DISPLAY 1.212766 (5991 428);
FORCEPROP 2 LAST CUSTOM_TXT_CDS <CON_PAGE_NUM> OF <CON_TOTAL_PAGES>
J 0
(5729 343);
DISPLAY 0.978723 (5729 343);
FORCEPROP 2 LAST CUSTOM_TXT_CDS <Q_PROJ>
J 0
(3793 427);
DISPLAY 1.212766 (3793 427);
FORCEPROP 2 LAST CUSTOM_TXT_CDS <Q_NUMBER>
J 0
(4772 428);
DISPLAY 1.212766 (4772 428);
FORCEPROP 2 LAST CUSTOM_TXT_CDS <NAME_2>
J 0
(3000 375);
FORCEPROP 2 LAST CUSTOM_TXT_CDS <NAME_1>
J 0
(3000 500);
FORCEPROP 1 LAST Q_TITLE SCM SMBUS BUS
J 0
(-3091 326);
DISPLAY 2.446809 (-3091 326);
PAINT GREEN (-3091 326);
FORCEPROP 1 LAST Q_DEPT 
J 1
(2412 374);
DISPLAY 1.957447 (2412 374);
PAINT GREEN (2412 374);
FORCEPROP 2 LAST CDS_XR_PAGE_TITLE CR-241 : @S9S_MB_2U_LIB.S9S_MB_2U(SCH_1):PAGE241
J 0
(-1715 5575);
DISPLAY 0.638298 (-1715 5575);
PAINT PINK (-1715 5575);
DISPLAY INVISIBLE (-1715 5575);
FORCEPROP 2 LAST PAGE_BORDER TRUE
J 0
(-1715 5575);
DISPLAY 0.638298 (-1715 5575);
PAINT PINK (-1715 5575);
DISPLAY INVISIBLE (-1715 5575);
FORCEPROP 1 LAST COMMENT_BODY TRUE
J 0
(6187 312);
DISPLAY 0.978723 (6187 312);
PAINT GREEN (6187 312);
DISPLAY INVISIBLE (6187 312);
FORCEPROP 1 LAST CDS_LMAN_SYM_OUTLINE -9475,6775,100,-125
J 0
(6175 325);
DISPLAY 0.468085 (6175 325);
PAINT GREEN (6175 325);
DISPLAY INVISIBLE (6175 325);
FORCEPROP 2 LAST CDS_LIB pure_quanta
J 0
(6175 325);
PAINT MONO (6175 325);
DISPLAY INVISIBLE (6175 325);
FORCEADD DNS..2
(5025 3300);
PAINT RED (5025 3300);
FORCEPROP 1 LAST COMMENT_BODY TRUE
R 1
J 0
(5100 3075);
DISPLAY 0.872340 (5100 3075);
PAINT GREEN (5100 3075);
DISPLAY INVISIBLE (5100 3075);
FORCEPROP 2 LAST CDS_LIB mstr_misc
J 0
(5025 3300);
DISPLAY INVISIBLE (5025 3300);
FORCEADD DNS..2
(5025 3250);
PAINT RED (5025 3250);
FORCEPROP 1 LAST COMMENT_BODY TRUE
R 1
J 0
(5100 3025);
DISPLAY 0.872340 (5100 3025);
PAINT GREEN (5100 3025);
DISPLAY INVISIBLE (5100 3025);
FORCEPROP 2 LAST CDS_LIB mstr_misc
J 0
(5025 3250);
DISPLAY INVISIBLE (5025 3250);
FORCEADD DNS..2
(5025 3650);
PAINT RED (5025 3650);
FORCEPROP 2 LAST CDS_LIB mstr_misc
J 0
(5025 3650);
DISPLAY INVISIBLE (5025 3650);
FORCEPROP 1 LAST COMMENT_BODY TRUE
R 1
J 0
(5100 3425);
DISPLAY 0.872340 (5100 3425);
PAINT GREEN (5100 3425);
DISPLAY INVISIBLE (5100 3425);
FORCEADD DNS..2
(5025 3700);
PAINT RED (5025 3700);
FORCEPROP 2 LAST CDS_LIB mstr_misc
J 0
(5025 3700);
DISPLAY INVISIBLE (5025 3700);
FORCEPROP 1 LAST COMMENT_BODY TRUE
R 1
J 0
(5100 3475);
DISPLAY 0.872340 (5100 3475);
PAINT GREEN (5100 3475);
DISPLAY INVISIBLE (5100 3475);
FORCEADD DNS..2
(5025 4325);
PAINT RED (5025 4325);
FORCEPROP 2 LAST CDS_LIB mstr_misc
J 0
(5025 4325);
DISPLAY INVISIBLE (5025 4325);
FORCEPROP 1 LAST COMMENT_BODY TRUE
R 1
J 0
(5100 4100);
DISPLAY 0.872340 (5100 4100);
PAINT GREEN (5100 4100);
DISPLAY INVISIBLE (5100 4100);
FORCEADD DNS..2
(5025 4375);
PAINT RED (5025 4375);
FORCEPROP 2 LAST CDS_LIB mstr_misc
J 0
(5025 4375);
DISPLAY INVISIBLE (5025 4375);
FORCEPROP 1 LAST COMMENT_BODY TRUE
R 1
J 0
(5100 4150);
DISPLAY 0.872340 (5100 4150);
PAINT GREEN (5100 4150);
DISPLAY INVISIBLE (5100 4150);
FORCEADD DNS..2
(5025 4025);
PAINT RED (5025 4025);
FORCEPROP 2 LAST CDS_LIB mstr_misc
J 0
(5025 4025);
DISPLAY INVISIBLE (5025 4025);
FORCEPROP 1 LAST COMMENT_BODY TRUE
R 1
J 0
(5100 3800);
DISPLAY 0.872340 (5100 3800);
PAINT GREEN (5100 3800);
DISPLAY INVISIBLE (5100 3800);
FORCEADD DNS..2
(5025 6075);
PAINT RED (5025 6075);
FORCEPROP 2 LAST CDS_LIB mstr_misc
J 0
(5025 6075);
DISPLAY INVISIBLE (5025 6075);
FORCEPROP 1 LAST COMMENT_BODY TRUE
R 1
J 0
(5100 5850);
DISPLAY 0.872340 (5100 5850);
PAINT GREEN (5100 5850);
DISPLAY INVISIBLE (5100 5850);
FORCEADD DNS..2
(5025 6025);
PAINT RED (5025 6025);
FORCEPROP 1 LAST COMMENT_BODY TRUE
R 1
J 0
(5100 5800);
DISPLAY 0.872340 (5100 5800);
PAINT GREEN (5100 5800);
DISPLAY INVISIBLE (5100 5800);
FORCEPROP 2 LAST CDS_LIB mstr_misc
J 0
(5025 6025);
DISPLAY INVISIBLE (5025 6025);
FORCEADD DNS..2
(5025 5825);
PAINT RED (5025 5825);
FORCEPROP 2 LAST CDS_LIB mstr_misc
J 0
(5025 5825);
DISPLAY INVISIBLE (5025 5825);
FORCEPROP 1 LAST COMMENT_BODY TRUE
R 1
J 0
(5100 5600);
DISPLAY 0.872340 (5100 5600);
PAINT GREEN (5100 5600);
DISPLAY INVISIBLE (5100 5600);
FORCEADD DNS..2
(5025 5775);
PAINT RED (5025 5775);
FORCEPROP 2 LAST CDS_LIB mstr_misc
J 0
(5025 5775);
DISPLAY INVISIBLE (5025 5775);
FORCEPROP 1 LAST COMMENT_BODY TRUE
R 1
J 0
(5100 5550);
DISPLAY 0.872340 (5100 5550);
PAINT GREEN (5100 5550);
DISPLAY INVISIBLE (5100 5550);
FORCEADD DNS..2
(5025 5575);
PAINT RED (5025 5575);
FORCEPROP 2 LAST CDS_LIB mstr_misc
J 0
(5025 5575);
DISPLAY INVISIBLE (5025 5575);
FORCEPROP 1 LAST COMMENT_BODY TRUE
R 1
J 0
(5100 5350);
DISPLAY 0.872340 (5100 5350);
PAINT GREEN (5100 5350);
DISPLAY INVISIBLE (5100 5350);
FORCEADD DNS..2
(5025 4975);
PAINT RED (5025 4975);
FORCEPROP 1 LAST COMMENT_BODY TRUE
R 1
J 0
(5100 4750);
DISPLAY 0.872340 (5100 4750);
PAINT GREEN (5100 4750);
DISPLAY INVISIBLE (5100 4750);
FORCEPROP 2 LAST CDS_LIB mstr_misc
J 0
(5025 4975);
DISPLAY INVISIBLE (5025 4975);
FORCEADD DNS..2
(5025 3025);
PAINT RED (5025 3025);
FORCEPROP 2 LAST CDS_LIB mstr_misc
J 0
(5025 3025);
DISPLAY INVISIBLE (5025 3025);
FORCEPROP 1 LAST COMMENT_BODY TRUE
R 1
J 0
(5100 2800);
DISPLAY 0.872340 (5100 2800);
PAINT GREEN (5100 2800);
DISPLAY INVISIBLE (5100 2800);
FORCEADD DNS..2
(5025 2750);
PAINT RED (5025 2750);
FORCEPROP 2 LAST CDS_LIB mstr_misc
J 0
(5025 2750);
DISPLAY INVISIBLE (5025 2750);
FORCEPROP 1 LAST COMMENT_BODY TRUE
R 1
J 0
(5100 2525);
DISPLAY 0.872340 (5100 2525);
PAINT GREEN (5100 2525);
DISPLAY INVISIBLE (5100 2525);
FORCEADD DNS..2
(5025 2675);
PAINT RED (5025 2675);
FORCEPROP 2 LAST CDS_LIB mstr_misc
J 0
(5025 2675);
DISPLAY INVISIBLE (5025 2675);
FORCEPROP 1 LAST COMMENT_BODY TRUE
R 1
J 0
(5100 2450);
DISPLAY 0.872340 (5100 2450);
PAINT GREEN (5100 2450);
DISPLAY INVISIBLE (5100 2450);
FORCEADD DNS..2
(5025 2950);
PAINT RED (5025 2950);
FORCEPROP 2 LAST CDS_LIB mstr_misc
J 0
(5025 2950);
DISPLAY INVISIBLE (5025 2950);
FORCEPROP 1 LAST COMMENT_BODY TRUE
R 1
J 0
(5100 2725);
DISPLAY 0.872340 (5100 2725);
PAINT GREEN (5100 2725);
DISPLAY INVISIBLE (5100 2725);
FORCEADD DNS..2
(5025 4925);
PAINT RED (5025 4925);
FORCEPROP 1 LAST COMMENT_BODY TRUE
R 1
J 0
(5100 4700);
DISPLAY 0.872340 (5100 4700);
PAINT GREEN (5100 4700);
DISPLAY INVISIBLE (5100 4700);
FORCEPROP 2 LAST CDS_LIB mstr_misc
J 0
(5025 4925);
DISPLAY INVISIBLE (5025 4925);
FORCEADD DNS..2
(5025 4075);
PAINT RED (5025 4075);
FORCEPROP 2 LAST CDS_LIB mstr_misc
J 0
(5025 4075);
DISPLAY INVISIBLE (5025 4075);
FORCEPROP 1 LAST COMMENT_BODY TRUE
R 1
J 0
(5100 3850);
DISPLAY 0.872340 (5100 3850);
PAINT GREEN (5100 3850);
DISPLAY INVISIBLE (5100 3850);
FORCEADD CAD_NOTE..1
(-2900 5300);
FORCEPROP 0 LAST S1 PLACE SMBUS SERIES RESISTOR CLOSE TO THE PCH
J 0
(-3050 5175);
DISPLAY 0.638298 (-3050 5175);
PAINT SKYBLUE (-3050 5175);
FORCEPROP 1 LAST COMMENT_BODY TRUE
J 0
(-2875 5400);
DISPLAY 0.978723 (-2875 5400);
DISPLAY INVISIBLE (-2875 5400);
FORCEPROP 2 LAST CDS_LIB logical_power
J 0
(-2900 5300);
PAINT MONO (-2900 5300);
DISPLAY INVISIBLE (-2900 5300);
FORCEADD DNS..2
(5025 5525);
PAINT RED (5025 5525);
FORCEPROP 1 LAST COMMENT_BODY TRUE
R 1
J 0
(5100 5300);
DISPLAY 0.872340 (5100 5300);
PAINT GREEN (5100 5300);
DISPLAY INVISIBLE (5100 5300);
FORCEPROP 2 LAST CDS_LIB mstr_misc
J 0
(5025 5525);
DISPLAY INVISIBLE (5025 5525);
WIRE 16 -1 (5550 6350)(5550 6075);
WIRE 16 2175 (-2700 2950)(1750 2950);
WIRE 16 2175 (1750 3225)(1750 2950);
WIRE 16 2175 (-2700 3225)(-2700 2950);
WIRE 16 2175 (-2700 3225)(1750 3225);
WIRE 16 -1 (-425 3050)(-2000 3050);
FORCEPROP 2 LAST SIG_NAME SMB_SML1_PMBUS_3V3AUX_PCH_SCL
J 0
(-1860 3060);
DISPLAY 0.680851 (-1860 3060);
PAINT WHITE (-1860 3060);
WIRE 16 -1 (-425 3000)(-2000 3000);
FORCEPROP 2 LAST SIG_NAME SMB_SML1_PMBUS_3V3AUX_PCH_SDA
J 0
(-1860 3010);
DISPLAY 0.680851 (-1860 3010);
PAINT WHITE (-1860 3010);
WIRE 16 -1 (-250 1800)(1275 1800);
FORCEPROP 2 LAST SIG_NAME SMB_VR_3V3AUX_SDA_R3
J 0
(265 1810);
DISPLAY 0.680851 (265 1810);
PAINT WHITE (265 1810);
WIRE 16 -1 (1275 750)(-250 750);
FORCEPROP 0 LAST SIG_NAME SMB_2_PLD_3V3AUX_SCL_R1
J 0
(415 760);
DISPLAY 0.680851 (415 760);
PAINT WHITE (415 760);
WIRE 16 -1 (-750 1850)(-450 1850);
WIRE 16 -1 (-750 2125)(-750 1850);
WIRE 16 -1 (-2025 2125)(-750 2125);
FORCEPROP 2 LAST SIG_NAME SMB_VR_3V3AUX_SCL_R
J 0
(-1910 2135);
DISPLAY 0.680851 (-1910 2135);
PAINT WHITE (-1910 2135);
WIRE 16 -1 (-750 2125)(-450 2125);
WIRE 16 -1 (-725 2450)(-425 2450);
WIRE 16 -1 (-725 2725)(-725 2450);
WIRE 16 -1 (-725 2725)(-425 2725);
WIRE 16 -1 (-2000 2725)(-725 2725);
FORCEPROP 2 LAST SIG_NAME SMB_VR_3V3AUX_SCL
J 0
(-1860 2735);
DISPLAY 0.680851 (-1860 2735);
PAINT WHITE (-1860 2735);
WIRE 16 -1 (1275 1025)(-250 1025);
FORCEPROP 0 LAST SIG_NAME SMB_1_PLD_3V3AUX_SCL_R1
J 0
(415 1035);
DISPLAY 0.680851 (415 1035);
PAINT WHITE (415 1035);
WIRE 16 -1 (1275 975)(-250 975);
FORCEPROP 0 LAST SIG_NAME SMB_1_PLD_3V3AUX_SDA_R1
J 0
(415 985);
DISPLAY 0.680851 (415 985);
PAINT WHITE (415 985);
WIRE 16 -1 (-250 1850)(1275 1850);
FORCEPROP 2 LAST SIG_NAME SMB_VR_3V3AUX_SCL_R3
J 0
(265 1860);
DISPLAY 0.680851 (265 1860);
PAINT WHITE (265 1860);
WIRE 16 -1 (-750 700)(-450 700);
WIRE 16 -1 (-750 975)(-2050 975);
FORCEPROP 0 LAST SIG_NAME SMB_1_PLD_3V3AUX_SDA
J 0
(-1960 985);
DISPLAY 0.680851 (-1960 985);
PAINT WHITE (-1960 985);
WIRE 16 -1 (-750 975)(-750 700);
WIRE 16 -1 (-450 975)(-750 975);
WIRE 16 -1 (-700 750)(-450 750);
WIRE 16 -1 (-700 1025)(-2050 1025);
FORCEPROP 0 LAST SIG_NAME SMB_1_PLD_3V3AUX_SCL
J 0
(-1960 1035);
DISPLAY 0.680851 (-1960 1035);
PAINT WHITE (-1960 1035);
WIRE 16 -1 (-700 1025)(-700 750);
WIRE 16 -1 (-450 1025)(-700 1025);
WIRE 16 -1 (-800 1800)(-450 1800);
WIRE 16 -1 (-800 2075)(-800 1800);
WIRE 16 -1 (-2025 2075)(-800 2075);
FORCEPROP 2 LAST SIG_NAME SMB_VR_3V3AUX_SDA_R
J 0
(-1910 2085);
DISPLAY 0.680851 (-1910 2085);
PAINT WHITE (-1910 2085);
WIRE 16 -1 (-800 2075)(-450 2075);
WIRE 16 -1 (-200 3475)(1325 3475);
FORCEPROP 2 LAST SIG_NAME SMB_SML1_PMBUS_HSC_SDA
J 0
(315 3485);
DISPLAY 0.680851 (315 3485);
PAINT WHITE (315 3485);
WIRE 16 -1 (-200 3525)(1325 3525);
FORCEPROP 2 LAST SIG_NAME SMB_SML1_PMBUS_HSC_SCL
J 0
(315 3535);
DISPLAY 0.680851 (315 3535);
PAINT WHITE (315 3535);
WIRE 16 -1 (-200 3875)(1325 3875);
FORCEPROP 2 LAST SIG_NAME SMB_SML1_PMBUS_HSC_SDA_R3
J 0
(315 3885);
DISPLAY 0.680851 (315 3885);
PAINT WHITE (315 3885);
WIRE 16 -1 (-200 3925)(1325 3925);
FORCEPROP 2 LAST SIG_NAME SMB_SML1_PMBUS_HSC_SCL_R3
J 0
(315 3935);
DISPLAY 0.680851 (315 3935);
PAINT WHITE (315 3935);
WIRE 16 -1 (-200 4275)(1325 4275);
FORCEPROP 2 LAST SIG_NAME SMB_SML0_ME_SCL
J 0
(315 4285);
DISPLAY 0.680851 (315 4285);
PAINT WHITE (315 4285);
WIRE 16 -1 (-225 4550)(1325 4550);
FORCEPROP 2 LAST SIG_NAME SMB_SML0_3V3AUX_PCH_SCL
J 0
(265 4560);
DISPLAY 0.680851 (265 4560);
PAINT WHITE (265 4560);
WIRE 16 -1 (1300 4800)(-225 4800);
FORCEPROP 2 LAST SIG_NAME SMB_HOST_CLK_GEN2_3V3AUX_SDA
J 0
(265 4810);
DISPLAY 0.702128 (265 4810);
PAINT WHITE (265 4810);
WIRE 16 -1 (1275 5125)(-250 5125);
FORCEPROP 2 LAST SIG_NAME SMB_HOST_CLK_BUF_3V3AUX_SDA
J 0
(240 5135);
DISPLAY 0.702128 (240 5135);
PAINT WHITE (240 5135);
WIRE 16 -1 (-800 5750)(-300 5750);
WIRE 16 -1 (-800 5750)(-800 6000);
WIRE 16 -1 (-800 6000)(1300 6000);
WIRE 16 -1 (-1125 6000)(-800 6000);
FORCEPROP 2 LAST SIG_NAME SMB_HOST_3V3AUX_SDA_R5
J 0
(365 6010);
DISPLAY 0.680851 (365 6010);
PAINT WHITE (365 6010);
WIRE 16 -1 (-725 5800)(-300 5800);
WIRE 16 -1 (-725 5800)(-725 6050);
WIRE 16 -1 (-725 6050)(1300 6050);
WIRE 16 -1 (-1125 6050)(-725 6050);
FORCEPROP 2 LAST SIG_NAME SMB_HOST_3V3AUX_SCL_R5
J 0
(365 6060);
DISPLAY 0.680851 (365 6060);
PAINT WHITE (365 6060);
WIRE 16 -1 (1350 6350)(-250 6350);
FORCEPROP 2 LAST SIG_NAME SMB_HOST_3V3AUX_SDA_R
J 0
(390 6360);
DISPLAY 0.680851 (390 6360);
PAINT WHITE (390 6360);
WIRE 16 -1 (1350 6400)(-250 6400);
FORCEPROP 2 LAST SIG_NAME SMB_HOST_3V3AUX_SCL_R
J 0
(390 6410);
DISPLAY 0.680851 (390 6410);
PAINT WHITE (390 6410);
WIRE 16 -1 (-2225 6725)(-450 6725);
FORCEPROP 2 LAST SIG_NAME SMB_HOST_3V3AUX_SCL
J 0
(-1835 6735);
DISPLAY 0.680851 (-1835 6735);
PAINT WHITE (-1835 6735);
WIRE 16 -1 (-450 6350)(-2200 6350);
FORCEPROP 2 LAST SIG_NAME SMB_HOST_3V3AUX_SDA_R4
J 0
(-1860 6360);
DISPLAY 0.680851 (-1860 6360);
PAINT WHITE (-1860 6360);
WIRE 16 -1 (-1325 6050)(-2200 6050);
FORCEPROP 2 LAST SIG_NAME SMB_HOST_3V3AUX_SCL
J 0
(-2185 6060);
DISPLAY 0.680851 (-2185 6060);
PAINT WHITE (-2185 6060);
WIRE 16 -1 (-1325 6000)(-2200 6000);
FORCEPROP 2 LAST SIG_NAME SMB_HOST_3V3AUX_SDA
J 0
(-2185 6010);
DISPLAY 0.680851 (-2185 6010);
PAINT WHITE (-2185 6010);
WIRE 16 -1 (-450 6400)(-2200 6400);
FORCEPROP 2 LAST SIG_NAME SMB_HOST_3V3AUX_SCL_R4
J 0
(-1860 6410);
DISPLAY 0.680851 (-1860 6410);
PAINT WHITE (-1860 6410);
WIRE 16 -1 (-2225 6675)(-450 6675);
FORCEPROP 2 LAST SIG_NAME SMB_HOST_3V3AUX_SDA
J 0
(-1835 6685);
DISPLAY 0.680851 (-1835 6685);
PAINT WHITE (-1835 6685);
WIRE 16 -1 (-850 5125)(-450 5125);
WIRE 16 -1 (-850 5450)(-850 5125);
WIRE 16 -1 (-450 5450)(-850 5450);
WIRE 16 -1 (-2200 5450)(-850 5450);
FORCEPROP 2 LAST SIG_NAME SMB_HOST_3V3AUX_SDA_R
J 0
(-2010 5460);
DISPLAY 0.680851 (-2010 5460);
PAINT WHITE (-2010 5460);
WIRE 16 -1 (-1975 4850)(-425 4850);
FORCEPROP 2 LAST SIG_NAME SMB_HOST_CLK_3V3AUX_SCL
J 0
(-1785 4860);
DISPLAY 0.702128 (-1785 4860);
PAINT WHITE (-1785 4860);
WIRE 16 -1 (-1975 4800)(-425 4800);
FORCEPROP 2 LAST SIG_NAME SMB_HOST_CLK_3V3AUX_SDA
J 0
(-1785 4810);
DISPLAY 0.702128 (-1785 4810);
PAINT WHITE (-1785 4810);
WIRE 16 -1 (-800 5175)(-450 5175);
WIRE 16 -1 (-800 5500)(-800 5175);
WIRE 16 -1 (-800 5500)(-450 5500);
WIRE 16 -1 (-2200 5500)(-800 5500);
FORCEPROP 2 LAST SIG_NAME SMB_HOST_3V3AUX_SCL_R
J 0
(-2010 5510);
DISPLAY 0.680851 (-2010 5510);
PAINT WHITE (-2010 5510);
WIRE 16 -1 (5100 2675)(5550 2675);
WIRE 16 -1 (5100 2725)(5550 2725);
WIRE 16 -1 (5550 2675)(5550 2725);
WIRE 16 -1 (5100 2975)(5550 2975);
WIRE 16 -1 (5550 2725)(5550 2975);
WIRE 16 -1 (5100 3025)(5550 3025);
WIRE 16 -1 (5550 2975)(5550 3025);
WIRE 16 -1 (5100 3250)(5550 3250);
WIRE 16 -1 (5550 3025)(5550 3250);
WIRE 16 -1 (5100 3300)(5550 3300);
WIRE 16 -1 (5550 3300)(5550 3250);
WIRE 16 -1 (5550 3650)(5100 3650);
WIRE 16 -1 (5550 3650)(5550 3300);
WIRE 16 -1 (5100 3700)(5550 3700);
WIRE 16 -1 (5550 3700)(5550 3650);
WIRE 16 -1 (5550 4025)(5100 4025);
WIRE 16 -1 (5550 4025)(5550 3700);
WIRE 16 -1 (5100 4075)(5550 4075);
WIRE 16 -1 (5550 4075)(5550 4025);
WIRE 16 -1 (5550 4325)(5550 4075);
WIRE 16 -1 (5550 4325)(5100 4325);
WIRE 16 -1 (5100 4375)(5550 4375);
WIRE 16 -1 (5550 4375)(5550 4325);
WIRE 16 -1 (5550 4925)(5100 4925);
WIRE 16 -1 (5550 4925)(5550 4375);
WIRE 16 -1 (5100 4975)(5550 4975);
WIRE 16 -1 (5550 4975)(5550 4925);
WIRE 16 -1 (5550 5525)(5100 5525);
WIRE 16 -1 (5550 5525)(5550 4975);
WIRE 16 -1 (5550 5575)(5100 5575);
WIRE 16 -1 (5550 5575)(5550 5525);
WIRE 16 -1 (5550 5775)(5100 5775);
WIRE 16 -1 (5550 5775)(5550 5575);
WIRE 16 -1 (5550 5825)(5100 5825);
WIRE 16 -1 (5550 5825)(5550 5775);
WIRE 16 -1 (5550 6025)(5100 6025);
WIRE 16 -1 (5550 6025)(5550 5825);
WIRE 16 -1 (5550 6075)(5100 6075);
WIRE 16 -1 (5550 6075)(5550 6025);
WIRE 16 -1 (1325 4500)(-225 4500);
FORCEPROP 2 LAST SIG_NAME SMB_SML0_3V3AUX_PCH_SDA
J 0
(265 4510);
DISPLAY 0.680851 (265 4510);
PAINT WHITE (265 4510);
WIRE 16 -1 (-200 4225)(1325 4225);
FORCEPROP 2 LAST SIG_NAME SMB_SML0_ME_SDA
J 0
(315 4235);
DISPLAY 0.680851 (315 4235);
PAINT WHITE (315 4235);
WIRE 16 -1 (1275 5500)(-250 5500);
FORCEPROP 2 LAST SIG_NAME SMB_HOST_CLK_3V3AUX_SCL
J 0
(240 5510);
DISPLAY 0.702128 (240 5510);
PAINT WHITE (240 5510);
WIRE 16 -1 (1275 5450)(-250 5450);
FORCEPROP 2 LAST SIG_NAME SMB_HOST_CLK_3V3AUX_SDA
J 0
(240 5460);
DISPLAY 0.702128 (240 5460);
PAINT WHITE (240 5460);
WIRE 16 -1 (1300 4850)(-225 4850);
FORCEPROP 2 LAST SIG_NAME SMB_HOST_CLK_GEN2_3V3AUX_SCL
J 0
(265 4860);
DISPLAY 0.702128 (265 4860);
PAINT WHITE (265 4860);
WIRE 16 -1 (-700 4275)(-400 4275);
WIRE 16 -1 (-700 4550)(-2000 4550);
FORCEPROP 2 LAST SIG_NAME SMB_SML0_3V3AUX_SCL
J 0
(-1860 4560);
DISPLAY 0.680851 (-1860 4560);
PAINT WHITE (-1860 4560);
WIRE 16 -1 (-700 4550)(-700 4275);
WIRE 16 -1 (-425 4550)(-700 4550);
WIRE 16 -1 (-750 4225)(-400 4225);
WIRE 16 -1 (-750 4500)(-2000 4500);
FORCEPROP 2 LAST SIG_NAME SMB_SML0_3V3AUX_SDA
J 0
(-1860 4510);
DISPLAY 0.680851 (-1860 4510);
PAINT WHITE (-1860 4510);
WIRE 16 -1 (-750 4500)(-750 4225);
WIRE 16 -1 (-425 4500)(-750 4500);
WIRE 16 -1 (-2000 3875)(-400 3875);
FORCEPROP 2 LAST SIG_NAME SMB_SML1_PMBUS_3V3AUX_PCH_SDA
J 0
(-1860 3885);
DISPLAY 0.680851 (-1860 3885);
PAINT WHITE (-1860 3885);
WIRE 16 -1 (-225 2675)(1300 2675);
FORCEPROP 2 LAST SIG_NAME SMB_VR_3V3AUX_SDA_R
J 0
(290 2685);
DISPLAY 0.680851 (290 2685);
PAINT WHITE (290 2685);
WIRE 16 -1 (1300 3000)(-225 3000);
FORCEPROP 2 LAST SIG_NAME SMB_PMBUS_SML1_ME_SDA
J 0
(265 3010);
DISPLAY 0.680851 (265 3010);
PAINT WHITE (265 3010);
WIRE 16 -1 (-2000 3925)(-400 3925);
FORCEPROP 2 LAST SIG_NAME SMB_SML1_PMBUS_3V3AUX_PCH_SCL
J 0
(-1860 3935);
DISPLAY 0.680851 (-1860 3935);
PAINT WHITE (-1860 3935);
WIRE 16 -1 (-250 2075)(1275 2075);
FORCEPROP 2 LAST SIG_NAME SMB_VR_3V3AUX_SDA_R2
J 0
(265 2085);
DISPLAY 0.680851 (265 2085);
PAINT WHITE (265 2085);
WIRE 16 -1 (-250 2125)(1275 2125);
FORCEPROP 2 LAST SIG_NAME SMB_VR_3V3AUX_SCL_R2
J 0
(265 2135);
DISPLAY 0.680851 (265 2135);
PAINT WHITE (265 2135);
WIRE 16 -1 (1275 700)(-250 700);
FORCEPROP 0 LAST SIG_NAME SMB_2_PLD_3V3AUX_SDA_R1
J 0
(415 710);
DISPLAY 0.680851 (415 710);
PAINT WHITE (415 710);
WIRE 16 -1 (-775 2400)(-425 2400);
WIRE 16 -1 (-775 2675)(-775 2400);
WIRE 16 -1 (-775 2675)(-425 2675);
WIRE 16 -1 (-2000 2675)(-775 2675);
FORCEPROP 2 LAST SIG_NAME SMB_VR_3V3AUX_SDA
J 0
(-1860 2685);
DISPLAY 0.680851 (-1860 2685);
PAINT WHITE (-1860 2685);
WIRE 16 -1 (-225 3050)(1300 3050);
FORCEPROP 2 LAST SIG_NAME SMB_PMBUS_SML1_ME_SCL
J 0
(265 3060);
DISPLAY 0.680851 (265 3060);
PAINT WHITE (265 3060);
WIRE 16 -1 (4900 4375)(3550 4375);
FORCEPROP 0 LAST CDS_PHYS_NET_NAME SMB_SENSOR_3V3AUX_SCL
J 0
(3765 4423);
PAINT MONO (3765 4423);
DISPLAY INVISIBLE (3765 4423);
FORCEPROP 2 LAST SIG_NAME I3C_BMC_SWB_SCL
J 0
(3665 4385);
DISPLAY 0.638298 (3665 4385);
PAINT WHITE (3665 4385);
WIRE 16 -1 (4900 4325)(3550 4325);
FORCEPROP 0 LAST CDS_PHYS_NET_NAME SMB_SENSOR_3V3AUX_SDA
J 0
(3765 4373);
PAINT MONO (3765 4373);
DISPLAY INVISIBLE (3765 4373);
FORCEPROP 2 LAST SIG_NAME I3C_BMC_SWB_SDA
J 0
(3665 4335);
DISPLAY 0.638298 (3665 4335);
PAINT WHITE (3665 4335);
WIRE 16 2175 (3050 4475)(4200 4475);
WIRE 16 2175 (4200 4475)(4200 4250);
WIRE 16 2175 (3050 4475)(3050 4250);
WIRE 16 2175 (3050 4250)(4200 4250);
WIRE 16 -1 (-225 2400)(1300 2400);
FORCEPROP 2 LAST SIG_NAME SMB_VR_3V3AUX_SDA_R1
J 0
(290 2410);
DISPLAY 0.680851 (290 2410);
PAINT WHITE (290 2410);
WIRE 16 -1 (-225 2450)(1300 2450);
FORCEPROP 2 LAST SIG_NAME SMB_VR_3V3AUX_SCL_R1
J 0
(290 2460);
DISPLAY 0.680851 (290 2460);
PAINT WHITE (290 2460);
WIRE 16 -1 (4900 3250)(3550 3250);
FORCEPROP 0 LAST CDS_PHYS_NET_NAME SMB_SENSOR_3V3AUX_SDA
J 0
(3765 3298);
PAINT MONO (3765 3298);
DISPLAY INVISIBLE (3765 3298);
FORCEPROP 2 LAST SIG_NAME SMB_1_BMC_GPU_SDA
J 0
(3665 3260);
DISPLAY 0.638298 (3665 3260);
PAINT WHITE (3665 3260);
WIRE 16 -1 (4900 3300)(3550 3300);
FORCEPROP 0 LAST CDS_PHYS_NET_NAME SMB_SENSOR_3V3AUX_SCL
J 0
(3765 3348);
PAINT MONO (3765 3348);
DISPLAY INVISIBLE (3765 3348);
FORCEPROP 2 LAST SIG_NAME SMB_1_BMC_GPU_SCL
J 0
(3665 3310);
DISPLAY 0.638298 (3665 3310);
PAINT WHITE (3665 3310);
WIRE 16 -1 (1275 5175)(-250 5175);
FORCEPROP 2 LAST SIG_NAME SMB_HOST_CLK_BUF_3V3AUX_SCL
J 0
(240 5185);
DISPLAY 0.702128 (240 5185);
PAINT WHITE (240 5185);
WIRE 16 -1 (-250 6675)(1350 6675);
FORCEPROP 2 LAST SIG_NAME SMB_HOST_3V3AUX_SDA_R4
J 0
(365 6685);
DISPLAY 0.680851 (365 6685);
PAINT WHITE (365 6685);
WIRE 16 -1 (-250 6725)(1350 6725);
FORCEPROP 2 LAST SIG_NAME SMB_HOST_3V3AUX_SCL_R4
J 0
(365 6735);
DISPLAY 0.680851 (365 6735);
PAINT WHITE (365 6735);
WIRE 16 -1 (1300 5800)(-100 5800);
FORCEPROP 2 LAST SIG_NAME SMB_HOST_BMC_3V3AUX_SCL
J 0
(390 5810);
DISPLAY 0.680851 (390 5810);
PAINT WHITE (390 5810);
WIRE 16 -1 (1300 5750)(-100 5750);
FORCEPROP 2 LAST SIG_NAME SMB_HOST_BMC_3V3AUX_SDA
J 0
(390 5760);
DISPLAY 0.680851 (390 5760);
PAINT WHITE (390 5760);
WIRE 16 -1 (-2000 3475)(-400 3475);
FORCEPROP 2 LAST SIG_NAME SMB_SML1_PMBUS_HSC_SDA_R3
J 0
(-1860 3485);
DISPLAY 0.680851 (-1860 3485);
PAINT WHITE (-1860 3485);
WIRE 16 -1 (-2000 3525)(-400 3525);
FORCEPROP 2 LAST SIG_NAME SMB_SML1_PMBUS_HSC_SCL_R3
J 0
(-1860 3535);
DISPLAY 0.680851 (-1860 3535);
PAINT WHITE (-1860 3535);
WIRE 16 -1 (-225 2725)(1300 2725);
FORCEPROP 2 LAST SIG_NAME SMB_VR_3V3AUX_SCL_R
J 0
(290 2735);
DISPLAY 0.680851 (290 2735);
PAINT WHITE (290 2735);
WIRE 16 -1 (3975 2050)(5625 2050);
FORCEPROP 2 LAST SIG_NAME I3C_SPD_DDRABCD_CPU0_BMC_SCL
J 0
(4640 2060);
DISPLAY 0.680851 (4640 2060);
PAINT WHITE (4640 2060);
WIRE 16 -1 (5625 2000)(3975 2000);
FORCEPROP 2 LAST SIG_NAME I3C_SPD_DDRABCD_CPU0_BMC_SDA
J 0
(4640 2010);
DISPLAY 0.680851 (4640 2010);
PAINT WHITE (4640 2010);
WIRE 16 -1 (3975 1750)(5625 1750);
FORCEPROP 2 LAST SIG_NAME I3C_SPD_DDREFGH_CPU0_BMC_SCL
J 0
(4640 1760);
DISPLAY 0.680851 (4640 1760);
PAINT WHITE (4640 1760);
WIRE 16 -1 (5625 1700)(3975 1700);
FORCEPROP 2 LAST SIG_NAME I3C_SPD_DDREFGH_CPU0_BMC_SDA
J 0
(4640 1710);
DISPLAY 0.680851 (4640 1710);
PAINT WHITE (4640 1710);
WIRE 16 -1 (3975 1425)(5625 1425);
FORCEPROP 2 LAST SIG_NAME I3C_SPD_DDRABCD_CPU1_BMC_SCL
J 0
(4640 1435);
DISPLAY 0.680851 (4640 1435);
PAINT WHITE (4640 1435);
WIRE 16 -1 (5625 1375)(3975 1375);
FORCEPROP 2 LAST SIG_NAME I3C_SPD_DDRABCD_CPU1_BMC_SDA
J 0
(4640 1385);
DISPLAY 0.680851 (4640 1385);
PAINT WHITE (4640 1385);
WIRE 16 -1 (3975 1125)(5625 1125);
FORCEPROP 2 LAST SIG_NAME I3C_SPD_DDREFGH_CPU1_BMC_SCL
J 0
(4640 1135);
DISPLAY 0.680851 (4640 1135);
PAINT WHITE (4640 1135);
WIRE 16 -1 (5625 1075)(3975 1075);
FORCEPROP 2 LAST SIG_NAME I3C_SPD_DDREFGH_CPU1_BMC_SDA
J 0
(4640 1085);
DISPLAY 0.680851 (4640 1085);
PAINT WHITE (4640 1085);
WIRE 16 -1 (3775 2050)(2400 2050);
FORCEPROP 2 LAST SIG_NAME I3C_SPD_DDRABCD_CPU0_BMC_R_SCL
J 0
(2515 2060);
DISPLAY 0.680851 (2515 2060);
PAINT WHITE (2515 2060);
WIRE 16 -1 (3775 2000)(2400 2000);
FORCEPROP 2 LAST SIG_NAME I3C_SPD_DDRABCD_CPU0_BMC_R_SDA
J 0
(2515 2010);
DISPLAY 0.680851 (2515 2010);
PAINT WHITE (2515 2010);
WIRE 16 -1 (3775 1750)(2400 1750);
FORCEPROP 2 LAST SIG_NAME I3C_SPD_DDREFGH_CPU0_BMC_R_SCL
J 0
(2515 1760);
DISPLAY 0.680851 (2515 1760);
PAINT WHITE (2515 1760);
WIRE 16 -1 (3775 1700)(2400 1700);
FORCEPROP 2 LAST SIG_NAME I3C_SPD_DDREFGH_CPU0_BMC_R_SDA
J 0
(2515 1710);
DISPLAY 0.680851 (2515 1710);
PAINT WHITE (2515 1710);
WIRE 16 -1 (3775 1425)(2400 1425);
FORCEPROP 2 LAST SIG_NAME I3C_SPD_DDRABCD_CPU1_BMC_R_SCL
J 0
(2515 1435);
DISPLAY 0.680851 (2515 1435);
PAINT WHITE (2515 1435);
WIRE 16 -1 (3775 1375)(2400 1375);
FORCEPROP 2 LAST SIG_NAME I3C_SPD_DDRABCD_CPU1_BMC_R_SDA
J 0
(2515 1385);
DISPLAY 0.680851 (2515 1385);
PAINT WHITE (2515 1385);
WIRE 16 -1 (3775 1075)(2400 1075);
FORCEPROP 2 LAST SIG_NAME I3C_SPD_DDREFGH_CPU1_BMC_R_SDA
J 0
(2515 1085);
DISPLAY 0.680851 (2515 1085);
PAINT WHITE (2515 1085);
WIRE 16 -1 (3775 1125)(2400 1125);
FORCEPROP 2 LAST SIG_NAME I3C_SPD_DDREFGH_CPU1_BMC_R_SCL
J 0
(2515 1135);
DISPLAY 0.680851 (2515 1135);
PAINT WHITE (2515 1135);
WIRE 16 -1 (3550 2675)(4900 2675);
FORCEPROP 0 LAST SIG_NAME SMB_OCP_V3_2_3V3AUX_SDA
J 0
(3640 2685);
DISPLAY 0.553191 (3640 2685);
PAINT WHITE (3640 2685);
WIRE 16 -1 (3550 2725)(4900 2725);
FORCEPROP 0 LAST SIG_NAME SMB_OCP_V3_2_3V3AUX_SCL
J 0
(3640 2735);
DISPLAY 0.553191 (3640 2735);
PAINT WHITE (3640 2735);
WIRE 16 -1 (4900 4075)(3550 4075);
FORCEPROP 0 LAST CDS_PHYS_NET_NAME SMB_SENSOR_3V3AUX_SCL
J 0
(3765 4123);
PAINT MONO (3765 4123);
DISPLAY INVISIBLE (3765 4123);
FORCEPROP 2 LAST SIG_NAME SMB_S3M_CPU_3V3AUX_SCL
J 0
(3665 4085);
DISPLAY 0.638298 (3665 4085);
PAINT WHITE (3665 4085);
WIRE 16 -1 (4900 4025)(3550 4025);
FORCEPROP 0 LAST CDS_PHYS_NET_NAME SMB_SENSOR_3V3AUX_SDA
J 0
(3765 4073);
PAINT MONO (3765 4073);
DISPLAY INVISIBLE (3765 4073);
FORCEPROP 2 LAST SIG_NAME SMB_S3M_CPU_3V3AUX_SDA
J 0
(3665 4035);
DISPLAY 0.638298 (3665 4035);
PAINT WHITE (3665 4035);
WIRE 16 -1 (4900 5575)(3550 5575);
FORCEPROP 2 LAST SIG_NAME SMB_SML1_PMBUS_3V3AUX_PCH_SCL
J 0
(3665 5585);
DISPLAY 0.680851 (3665 5585);
PAINT WHITE (3665 5585);
WIRE 16 -1 (4900 2975)(3550 2975);
FORCEPROP 2 LAST SIG_NAME SMB_OCP_SFF_3V3AUX_SDA
J 0
(3640 2985);
DISPLAY 0.638298 (3640 2985);
PAINT WHITE (3640 2985);
WIRE 16 -1 (4900 3025)(3550 3025);
FORCEPROP 2 LAST SIG_NAME SMB_OCP_SFF_3V3AUX_SCL
J 0
(3640 3035);
DISPLAY 0.638298 (3640 3035);
PAINT WHITE (3640 3035);
WIRE 16 -1 (4900 6075)(3550 6075);
FORCEPROP 2 LAST SIG_NAME SMB_HOST_3V3AUX_SCL
J 0
(3665 6085);
DISPLAY 0.680851 (3665 6085);
PAINT WHITE (3665 6085);
WIRE 16 -1 (4900 3700)(3550 3700);
FORCEPROP 0 LAST CDS_PHYS_NET_NAME SMB_SENSOR_3V3AUX_SCL
J 0
(3765 3748);
PAINT MONO (3765 3748);
DISPLAY INVISIBLE (3765 3748);
FORCEPROP 2 LAST SIG_NAME SMB_2_BMC_GPU_SCL
J 0
(3665 3710);
DISPLAY 0.638298 (3665 3710);
PAINT WHITE (3665 3710);
WIRE 16 -1 (4900 3650)(3550 3650);
FORCEPROP 0 LAST CDS_PHYS_NET_NAME SMB_SENSOR_3V3AUX_SDA
J 0
(3765 3698);
PAINT MONO (3765 3698);
DISPLAY INVISIBLE (3765 3698);
FORCEPROP 2 LAST SIG_NAME SMB_2_BMC_GPU_SDA
J 0
(3665 3660);
DISPLAY 0.638298 (3665 3660);
PAINT WHITE (3665 3660);
WIRE 16 -1 (3550 4925)(4900 4925);
FORCEPROP 0 LAST CDS_PHYS_NET_NAME SMB_FAN_3V3AUX_SDA
J 0
(3590 4973);
PAINT MONO (3590 4973);
DISPLAY INVISIBLE (3590 4973);
FORCEPROP 2 LAST SIG_NAME SMB_FAN_3V3AUX_SDA
J 0
(3665 4935);
DISPLAY 0.638298 (3665 4935);
PAINT WHITE (3665 4935);
WIRE 16 -1 (3550 4975)(4900 4975);
FORCEPROP 0 LAST CDS_PHYS_NET_NAME SMB_FAN_3V3AUX_SCL
J 0
(3590 5023);
PAINT MONO (3590 5023);
DISPLAY INVISIBLE (3590 5023);
FORCEPROP 2 LAST SIG_NAME SMB_FAN_3V3AUX_SCL
J 0
(3665 4985);
DISPLAY 0.638298 (3665 4985);
PAINT WHITE (3665 4985);
WIRE 16 -1 (4900 6025)(3550 6025);
FORCEPROP 2 LAST SIG_NAME SMB_HOST_3V3AUX_SDA
J 0
(3665 6035);
DISPLAY 0.680851 (3665 6035);
PAINT WHITE (3665 6035);
WIRE 16 -1 (4900 5775)(3550 5775);
FORCEPROP 2 LAST SIG_NAME SMB_SML0_3V3AUX_SDA
J 0
(3665 5785);
DISPLAY 0.680851 (3665 5785);
PAINT WHITE (3665 5785);
WIRE 16 -1 (4900 5525)(3550 5525);
FORCEPROP 2 LAST SIG_NAME SMB_SML1_PMBUS_3V3AUX_PCH_SDA
J 0
(3665 5535);
DISPLAY 0.680851 (3665 5535);
PAINT WHITE (3665 5535);
WIRE 16 -1 (4900 5825)(3550 5825);
FORCEPROP 2 LAST SIG_NAME SMB_SML0_3V3AUX_SCL
J 0
(3665 5835);
DISPLAY 0.680851 (3665 5835);
PAINT WHITE (3665 5835);
DOT 1 (-725 2725);
DOT 1 (-850 5450);
DOT 1 (-800 5500);
DOT 1 (-725 6050);
DOT 1 (-800 6000);
DOT 1 (-750 4500);
DOT 1 (-700 4550);
DOT 1 (-775 2675);
DOT 1 (-750 2125);
DOT 1 (-800 2075);
DOT 1 (-700 1025);
DOT 1 (-750 975);
DOT 1 (5550 4375);
DOT 1 (5550 3700);
DOT 1 (5550 5575);
DOT 1 (5550 6025);
DOT 1 (5550 5825);
DOT 1 (5550 5525);
DOT 1 (5550 5775);
DOT 1 (5550 4975);
DOT 1 (5550 4025);
DOT 1 (5550 3650);
DOT 1 (5550 4925);
DOT 1 (5550 6075);
DOT 1 (5550 4325);
DOT 1 (5550 4075);
DOT 1 (5550 2975);
DOT 1 (5550 3025);
DOT 1 (5550 3250);
DOT 1 (5550 3300);
DOT 1 (5550 2725);
FORCENOTE
VR_PU5
(1300 2175) 0;
DISPLAY LEFT (1300 2175);
DISPLAY 1.021277 (1300 2175);
PAINT SKYBLUE (1300 2175);
FORCENOTE
20220105 CHANGE NET NAME
(-1250 3250) 0;
DISPLAY LEFT (-1250 3250);
DISPLAY 1.595745 (-1250 3250);
PAINT PINK (-1250 3250);
FORCENOTE
VR_PU14
(1300 1900) 0;
DISPLAY LEFT (1300 1900);
DISPLAY 1.021277 (1300 1900);
PAINT SKYBLUE (1300 1900);
FORCENOTE
PCH
(1425 4600) 0;
DISPLAY LEFT (1425 4600);
DISPLAY 1.021277 (1425 4600);
PAINT SKYBLUE (1425 4600);
FORCENOTE
PCH
(1350 5850) 0;
DISPLAY LEFT (1350 5850);
DISPLAY 1.021277 (1350 5850);
PAINT SKYBLUE (1350 5850);
FORCENOTE
ME NODE
(1375 4325) 0;
DISPLAY LEFT (1375 4325);
DISPLAY 1.021277 (1375 4325);
PAINT SKYBLUE (1375 4325);
FORCENOTE
ME NODE
(1350 3100) 0;
DISPLAY LEFT (1350 3100);
DISPLAY 1.021277 (1350 3100);
PAINT SKYBLUE (1350 3100);
FORCENOTE
VR
(1375 2775) 0;
DISPLAY LEFT (1375 2775);
DISPLAY 1.021277 (1375 2775);
PAINT SKYBLUE (1375 2775);
FORCENOTE
I3C
(3725 2275) 0;
DISPLAY LEFT (3725 2275);
DISPLAY 3.148936 (3725 2275);
FORCENOTE
20220113 CHANGE NET NAME
(3050 4525) 0;
DISPLAY LEFT (3050 4525);
DISPLAY 1.063830 (3050 4525);
PAINT WHITE (3050 4525);
FORCENOTE
HSC
(1400 3575) 0;
DISPLAY LEFT (1400 3575);
DISPLAY 1.021277 (1400 3575);
PAINT SKYBLUE (1400 3575);
QUIT
